%FSTAX23Y23*%
%MOIN*%
%SFA1B1*%

%IPPOS*%
%ADD13C,0.010000*%
%ADD19C,0.008000*%
%ADD21C,0.005000*%
%ADD50R,0.028000X0.165000*%
%ADD51R,0.028000X0.126000*%
%ADD62R,0.057090X0.045280*%
%ADD64R,0.025200X0.026770*%
%ADD71R,0.045280X0.057090*%
%ADD72R,0.026770X0.025200*%
%ADD77R,0.082870X0.044090*%
%ADD143C,0.120000*%
%ADD150C,0.250000*%
%ADD153C,0.020000*%
%ADD157C,0.031500*%
%ADD158C,0.065980*%
%ADD159C,0.061020*%
%ADD160R,0.061020X0.061020*%
%ADD161C,0.075000*%
%ADD162C,0.098430*%
%ADD163O,0.088580X0.177170*%
%ADD164O,0.177170X0.088580*%
%ADD165O,0.196850X0.098430*%
%ADD166C,0.112000*%
%ADD167C,0.021660*%
%ADD168C,0.055000*%
%ADD169R,0.055000X0.055000*%
%ADD170C,0.050000*%
%ADD171C,0.016000*%
%ADD172C,0.200000*%
%ADD173R,0.073820X0.067910*%
%LNgrandmaster-1*%
%LPD*%
G36*
X04349Y04334D02*
X02014D01*
X02011Y04333*
X02009Y04331*
X02007Y04329*
X02006Y04326*
Y04293*
X02007Y0429*
X02007Y04289*
Y04226*
X02007Y04225*
X02006Y04222*
Y04186*
X02006Y04185*
X02007Y04184*
X02007Y04184*
X02007Y04183*
X02008Y04182*
X02008Y04181*
X02008Y04181*
X02009Y04181*
X02009Y0418*
X0201Y04179*
X02012Y04175*
X02008Y04167*
X02007Y04157*
X02008Y04148*
X02012Y04139*
X0201Y04135*
X02009Y04135*
X02009Y04134*
X02008Y04134*
X02008Y04134*
X02008Y04133*
X02007Y04131*
X02007Y04131*
X02007Y04131*
X02006Y0413*
X02006Y04128*
Y04086*
X02006Y04085*
X02007Y04084*
X02007Y04084*
X02007Y04083*
X02008Y04082*
X02008Y04081*
X02008Y04081*
X02009Y04081*
X02009Y0408*
X0201Y04079*
X02012Y04075*
X02008Y04067*
X02007Y04057*
X02008Y04048*
X02012Y04039*
X0201Y04035*
X02009Y04035*
X02009Y04034*
X02008Y04034*
X02008Y04034*
X02008Y04033*
X02007Y04031*
X02007Y04031*
X02007Y04031*
X02006Y0403*
X02006Y04028*
Y0385*
X02006Y03849*
X02007Y03847*
X02007Y03847*
X02007Y03847*
X02008Y03846*
X02009Y03844*
X02009Y03844*
X02009Y03844*
X0201Y03844*
X02011Y03843*
X02014Y03841*
X02013Y03836*
X02013Y03835*
X02013Y03834*
X02009Y03831*
X02004Y03832*
X01998Y03831*
X01993Y03827*
X01989Y03822*
X01988Y03816*
X01989Y03809*
X01993Y03804*
X01998Y038*
X02004Y03799*
X02006Y03798*
Y02718*
X02007Y02714*
X02009Y02712*
X02011Y0271*
X02014Y02709*
X02349*
X02352Y0271*
X02355Y02712*
X02357Y02714*
X02358Y02718*
Y02833*
X02387*
X02402Y02818*
Y02792*
X02403Y02789*
X02402Y02788*
X02404Y02782*
X02407Y02777*
X02413Y02773*
X02419Y02772*
X02425Y02773*
X0243Y02777*
X02431Y02777*
X02437Y02777*
X02443Y02766*
X02454Y02753*
X02467Y02742*
X02482Y02733*
X02497Y02727*
X02514Y02723*
X02531Y02721*
X02548Y02723*
X02564Y02727*
X0258Y02733*
X02595Y02742*
X02608Y02753*
X02619Y02766*
X02627Y0278*
X02634Y02796*
X02638Y02813*
X02639Y0283*
X02638Y02846*
X02635Y02857*
X02638Y0286*
X02643Y02864*
X02646Y02869*
X02648Y02876*
X02646Y02882*
X02646Y02883*
Y0294*
X02669*
Y02959*
X02681*
X02685Y0296*
X02689Y02962*
X02708Y02981*
X02732*
Y03024*
X02691*
Y02999*
X02676Y02983*
X02669*
Y03002*
X02596*
Y0294*
X02619*
Y029*
X02614Y02898*
X02608Y02906*
X02595Y02917*
X0258Y02926*
X02564Y02933*
X02548Y02937*
X02531Y02938*
X02514Y02937*
X02497Y02933*
X02482Y02926*
X02467Y02917*
X02454Y02906*
X02443Y02893*
X02434Y02879*
X02428Y02863*
X02424Y02846*
X02423Y02841*
X02419Y02839*
X02407Y02851*
Y02874*
X02358*
Y02907*
X02358*
Y0298*
X02358*
Y03012*
X02384*
Y03072*
X02358*
Y03091*
X02384*
Y03109*
X02405*
X02407Y03106*
X02408Y03106*
Y031*
X02405Y03098*
X024Y03091*
X02398Y03082*
X024Y03073*
X02405Y03065*
X02413Y0306*
X02422Y03058*
X02431Y0306*
X02438Y03065*
X02443Y03073*
X02445Y03082*
X02443Y03091*
X02438Y03098*
X02432Y03102*
X02431Y03105*
X02431Y03108*
X02433Y03112*
X02435Y03118*
X02433Y03124*
X0243Y0313*
X02424Y03133*
X02418Y03134*
X02413Y03133*
X02384*
Y03151*
X02358*
Y0317*
X02384*
Y03187*
X02403*
X02407Y03184*
X02414Y03183*
X0242Y03184*
X02425Y03188*
X02429Y03193*
X0243Y03199*
X02429Y03206*
X02425Y03211*
X02425Y03211*
X02426Y03217*
X02431Y03218*
X02438Y03223*
X02443Y0323*
X02445Y03239*
X02443Y03248*
X02438Y03256*
X02431Y03261*
X02422Y03263*
X02413Y03261*
X02405Y03256*
X024Y03248*
X02398Y03239*
X024Y0323*
X02405Y03223*
X02409Y0322*
X02408Y03215*
X02407Y03214*
X02403Y03212*
X02384*
Y0323*
X02358*
Y03249*
X02384*
Y03265*
X02397*
X02402Y03266*
X02407Y03269*
X02416Y03279*
X0242Y03279*
X02425Y03283*
X02428Y03288*
X0243Y03295*
X02428Y03301*
X02425Y03306*
X0242Y0331*
X02413Y03311*
X02407Y0331*
X02402Y03306*
X02398Y03301*
X02398Y03298*
X02392Y03292*
X02384*
Y03309*
X02358*
Y03322*
X02674Y03639*
X02674Y03639*
X02675Y03639*
X02675Y0364*
X02676Y03641*
X02676Y03642*
X02676Y03642*
X02679Y03644*
X02686Y03645*
X02691Y03649*
X02694Y03654*
X02695Y03659*
X02696Y03661*
X02698Y03664*
X02698Y03664*
X02699Y03664*
X027Y03665*
X02701Y03665*
X02701Y03666*
X02701Y03666*
X02713Y03677*
X0352*
X03522Y03672*
X0352Y03671*
X03516Y03666*
X03515Y0366*
X03516Y03653*
X0352Y03648*
X03525Y03644*
X03531Y03643*
X03538Y03644*
X03543Y03648*
X03546Y03653*
X03548Y0366*
X03546Y03666*
X03543Y03671*
X03541Y03672*
X03542Y03677*
X03804*
X03807Y03678*
X0381Y0368*
Y0368*
X03913Y03783*
X03915Y03786*
X03916Y03789*
X0392Y03793*
X03939*
X04037Y03696*
Y03675*
X04034Y03671*
X04033Y03665*
X04034Y03658*
X04038Y03653*
X04043Y03649*
X04049Y03648*
X04056Y03649*
X04061Y03653*
X04064Y03658*
X04066Y03665*
X04064Y03671*
X04062Y03675*
Y03701*
X04061Y03705*
X04058Y03709*
X03953Y03814*
X03952Y03815*
X03951Y03821*
X04068Y03937*
X04181*
X04341Y03777*
Y03662*
X0385Y03171*
X03845Y03174*
X03846Y03176*
X03844Y03182*
X03841Y03187*
X03836Y03191*
X03829Y03192*
X03823Y03191*
X03818Y03187*
X03814Y03182*
X03813Y03176*
X03814Y03169*
X03818Y03164*
X03823Y0316*
X03829Y03159*
X03831Y0316*
X03834Y03155*
X03824Y03146*
Y02201*
X04154Y01871*
X06687*
X06688Y01869*
X06693Y01865*
X06699Y01864*
X06706Y01865*
X06711Y01869*
X06712Y01871*
X06901*
Y01649*
X06637Y01385*
X06635Y01387*
X06628Y01388*
X06622Y01387*
X06617Y01383*
X06613Y01378*
X06612Y01372*
X06613Y01365*
X06615Y01363*
X06584Y01331*
X06582Y01329*
X06581Y01326*
Y01241*
X06582Y01237*
X06584Y01235*
X06644Y01175*
X06646Y01173*
X06649Y01172*
X06779*
X06782Y01173*
X06785Y01175*
X0693Y01319*
X06934Y01317*
Y01216*
X06329Y00611*
X03784*
X02638Y01757*
X02638Y01758*
X02641Y01763*
X02643Y0177*
X02641Y01776*
X02638Y01781*
X02633Y01785*
X02626Y01786*
X0262Y01785*
X02615Y01781*
X02614Y01781*
X02425Y0197*
X02424Y01973*
X02421Y01978*
X02416Y01982*
X02413Y01982*
X01355Y0304*
Y04162*
X01357Y04163*
X0136Y04168*
X01361Y04175*
X0136Y04181*
X01357Y04186*
X01355Y04187*
Y04341*
X01709*
X01712Y04336*
X01711Y04335*
X0171Y04329*
X01711Y04323*
X01715Y04317*
X0172Y04314*
X01726Y04313*
X01733Y04314*
X01738Y04317*
X01741Y04323*
X01743Y04329*
X01741Y04335*
X01741Y04336*
X01744Y04341*
X01771*
X01774Y04336*
X01773Y04335*
X01772Y04329*
X01773Y04323*
X01777Y04317*
X01782Y04314*
X01788Y04313*
X01795Y04314*
X018Y04317*
X01803Y04323*
X01805Y04329*
X01803Y04335*
X01803Y04336*
X01806Y04341*
X04349*
Y04334*
G37*
G36*
X06504Y04151D02*
Y04111D01*
X06503Y04106*
X06502Y04093*
X06503Y0408*
X06504Y04075*
Y0372*
X06501Y03716*
X06314Y03717*
X06313Y03717*
X06312Y03717*
X06311Y03717*
X0631Y03717*
X0631Y03716*
X06309Y03716*
X06309Y03715*
X06308Y03715*
X06307Y03714*
X06307Y03714*
X06306Y03712*
X06301Y03716*
X06294Y03717*
X06288Y03716*
X06286Y03714*
X06281Y03715*
X0628Y03715*
X0628Y03716*
X06279Y03716*
X06278Y03717*
X06278Y03717*
X06277Y03717*
X06276Y03717*
X06275Y03717*
X05989Y03719*
X05989*
X05989*
X05988Y03718*
X05986Y03718*
X05986Y03718*
X05986*
X05985Y03717*
X05984Y03716*
X05984Y03716*
X05984Y03716*
X05874Y03606*
X05872Y03604*
X05871Y03601*
Y03451*
X05872Y03447*
X05874Y03445*
X06326Y02992*
Y02397*
X06304Y02376*
X06289*
X06287Y02381*
X06289Y02384*
X06291Y02391*
X06289Y02397*
X06286Y02402*
X06281Y02406*
X06274Y02407*
X06268Y02406*
X06263Y02402*
X06259Y02397*
X06258Y02391*
X06259Y02384*
X06262Y02381*
X0626Y02376*
X04639*
X04349Y02666*
Y02712*
X04351Y02713*
X04354Y02718*
X04356Y02725*
X04354Y02731*
X04351Y02736*
X04349Y02737*
Y03133*
X0435Y03135*
X04349Y03136*
Y03781*
X04184Y03946*
X04064*
X03937Y03818*
X0384*
X03836Y03821*
X03829Y03822*
X03823Y03821*
X03818Y03817*
X03814Y03812*
X03813Y03806*
X03814Y03799*
X03818Y03794*
X03823Y0379*
X03829Y03789*
X03836Y0379*
X0384Y03793*
X03906*
X03907Y03789*
X03804Y03686*
X02709*
X02695Y03672*
X02691Y03672*
X02686Y03676*
X02679Y03677*
X02673Y03676*
X02668Y03672*
X02664Y03667*
X02663Y03661*
X02664Y03654*
X02668Y03649*
X02668Y03644*
X02349Y03326*
Y03309*
X02285*
Y03249*
X02349*
Y0323*
X02285*
Y0317*
X02349*
Y03151*
X02285*
Y03091*
X02349*
Y02718*
X02014*
Y03803*
X02016Y03804*
X02019Y03809*
X02021Y03816*
X02021Y03816*
X02021Y03817*
X02025Y0382*
X02029Y03819*
X02036Y0382*
X02041Y03824*
X02044Y03829*
X02046Y03836*
X02044Y03842*
X02041Y03847*
X02036Y03851*
X02029Y03852*
X02023Y03851*
X02019Y03848*
X02014Y0385*
Y04028*
X02019Y04031*
X02025Y04026*
X02034Y04023*
X02043Y04022*
X02052Y04023*
X02061Y04026*
X02068Y04032*
X02074Y04039*
X02077Y04048*
X02079Y04057*
X02077Y04067*
X02074Y04075*
X02068Y04083*
X02061Y04088*
X02052Y04092*
X02043Y04093*
X02034Y04092*
X02025Y04088*
X02019Y04084*
X02014Y04086*
Y04128*
X02019Y04131*
X02025Y04126*
X02034Y04123*
X02043Y04122*
X02052Y04123*
X02061Y04126*
X02068Y04132*
X02074Y04139*
X02077Y04148*
X02079Y04157*
X02077Y04167*
X02074Y04175*
X02068Y04183*
X02061Y04188*
X02052Y04192*
X02043Y04193*
X02034Y04192*
X02025Y04188*
X02019Y04184*
X02014Y04186*
Y04222*
X02078*
Y04293*
X02014*
Y04326*
X06329*
X06504Y04151*
G37*
G36*
X06275Y03709D02*
X06279Y03704D01*
X06278Y03701*
X06279Y03694*
X06283Y03689*
X06288Y03685*
X06294Y03684*
X06301Y03685*
X06306Y03689*
X06309Y03694*
X06311Y03701*
X0631Y03704*
X06314Y03709*
X07024Y03706*
X07087Y03643*
Y01488*
X06779Y01181*
X06649*
X06589Y01241*
Y01326*
X06621Y01357*
X06622Y01356*
X06628Y01355*
X06635Y01356*
X0664Y0136*
X06643Y01365*
X06645Y01372*
X06643Y01378*
X06643Y01379*
X06909Y01646*
Y01991*
X06819Y02081*
X06409*
X06399Y02091*
X06401Y02095*
X06402Y02095*
X06407Y02099*
X0641Y02104*
X06412Y02111*
X0641Y02117*
X06407Y02122*
X06402Y02126*
X06395Y02127*
X06389Y02126*
X06384Y02122*
X0638Y02117*
X0638Y02116*
X06375Y02115*
X06334Y02156*
Y02996*
X05879Y03451*
Y03601*
X05989Y03711*
X06275Y03709*
G37*
%LNgrandmaster-2*%
%LPC*%
G36*
X01493Y04289D02*
X01422D01*
Y04218*
X01493*
Y04289*
G37*
G36*
X01569Y04187D02*
X01563Y04186D01*
X01558Y04182*
X01554Y04177*
X01553Y04171*
X01554Y04165*
X01558Y04159*
X01563Y04156*
X01569Y04154*
X01576Y04156*
X01581Y04159*
X01584Y04165*
X01586Y04171*
X01584Y04177*
X01581Y04182*
X01576Y04186*
X01569Y04187*
G37*
G36*
X01779Y04172D02*
X01773Y04171D01*
X01768Y04167*
X01764Y04162*
X01763Y04156*
X01764Y04149*
X01768Y04144*
X01773Y0414*
X01779Y04139*
X01786Y0414*
X01791Y04144*
X01794Y04149*
X01796Y04156*
X01794Y04162*
X01791Y04167*
X01786Y04171*
X01779Y04172*
G37*
G36*
X01457Y04189D02*
X01448Y04188D01*
X01439Y04184*
X01432Y04179*
X01426Y04171*
X01423Y04163*
X01421Y04153*
X01423Y04144*
X01426Y04136*
X01432Y04128*
X01439Y04122*
X01448Y04119*
X01457Y04118*
X01466Y04119*
X01475Y04122*
X01483Y04128*
X01488Y04136*
X01492Y04144*
X01493Y04153*
X01492Y04163*
X01488Y04171*
X01483Y04179*
X01475Y04184*
X01466Y04188*
X01457Y04189*
G37*
G36*
X01749Y04126D02*
X01743Y04125D01*
X01738Y04121*
X01734Y04116*
X01733Y0411*
X01734Y04103*
X01738Y04098*
X01743Y04094*
X01749Y04093*
X01756Y04094*
X01761Y04098*
X01764Y04103*
X01766Y0411*
X01764Y04116*
X01761Y04121*
X01756Y04125*
X01749Y04126*
G37*
G36*
X01691Y04095D02*
X01685Y04094D01*
X0168Y0409*
X01676Y04085*
X01675Y04079*
X01676Y04072*
X0168Y04067*
X01685Y04063*
X01691Y04062*
X01698Y04063*
X01703Y04067*
X01706Y04072*
X01708Y04079*
X01706Y04085*
X01703Y0409*
X01698Y04094*
X01691Y04095*
G37*
G36*
X01457Y04089D02*
X01448Y04088D01*
X01439Y04084*
X01432Y04079*
X01426Y04071*
X01423Y04063*
X01421Y04053*
X01423Y04044*
X01426Y04036*
X01432Y04028*
X01439Y04022*
X01448Y04019*
X01457Y04018*
X01466Y04019*
X01475Y04022*
X01483Y04028*
X01488Y04036*
X01492Y04044*
X01493Y04053*
X01492Y04063*
X01488Y04071*
X01483Y04079*
X01475Y04084*
X01466Y04088*
X01457Y04089*
G37*
G36*
X01903Y04034D02*
X01897Y04033D01*
X01892Y04029*
X01888Y04024*
X01887Y04018*
X01888Y04011*
X01892Y04006*
X01897Y04002*
X01903Y04001*
X0191Y04002*
X01915Y04006*
X01918Y04011*
X0192Y04018*
X01918Y04024*
X01915Y04029*
X0191Y04033*
X01903Y04034*
G37*
G36*
X01408Y03996D02*
X01402Y03995D01*
X01396Y03991*
X01393Y03986*
X01392Y0398*
X01393Y03974*
X01396Y03968*
X01402Y03965*
X01408Y03964*
X01414Y03965*
X0142Y03968*
X01423Y03974*
X01424Y0398*
X01423Y03986*
X0142Y03991*
X01414Y03995*
X01408Y03996*
G37*
G36*
X04085Y03908D02*
X04079Y03907D01*
X04074Y03903*
X0407Y03898*
X04069Y03892*
X0407Y03885*
X04074Y0388*
X04079Y03876*
X04085Y03875*
X04092Y03876*
X04097Y0388*
X041Y03885*
X04102Y03892*
X041Y03898*
X04097Y03903*
X04092Y03907*
X04085Y03908*
G37*
G36*
X04194Y039D02*
X04188Y03899D01*
X04183Y03895*
X04179Y0389*
X04178Y03884*
X04179Y03877*
X04183Y03872*
X04188Y03868*
X04194Y03867*
X04201Y03868*
X04206Y03872*
X04209Y03877*
X04211Y03884*
X04209Y0389*
X04206Y03895*
X04201Y03899*
X04194Y039*
G37*
G36*
X04039Y038D02*
X04033Y03799D01*
X04028Y03795*
X04024Y0379*
X04023Y03784*
X04024Y03777*
X04028Y03772*
X04033Y03768*
X04039Y03767*
X04046Y03768*
X04051Y03772*
X04054Y03777*
X04056Y03784*
X04054Y0379*
X04051Y03795*
X04046Y03799*
X04039Y038*
G37*
G36*
X01849Y03717D02*
X01843Y03716D01*
X01838Y03712*
X01834Y03707*
X01833Y03701*
X01834Y03694*
X01838Y03689*
X01843Y03685*
X01849Y03684*
X01856Y03685*
X01861Y03689*
X01864Y03694*
X01866Y03701*
X01864Y03707*
X01861Y03712*
X01856Y03716*
X01849Y03717*
G37*
G36*
X01754Y03677D02*
X01748Y03676D01*
X01743Y03672*
X01739Y03667*
X01738Y03661*
X01739Y03654*
X01743Y03649*
X01748Y03645*
X01754Y03644*
X01761Y03645*
X01766Y03649*
X01769Y03654*
X01771Y03661*
X01769Y03667*
X01766Y03672*
X01761Y03676*
X01754Y03677*
G37*
G36*
X03424Y03652D02*
X03418Y03651D01*
X03413Y03647*
X03409Y03642*
X03408Y03636*
X03409Y03629*
X03413Y03624*
X03418Y0362*
X03424Y03619*
X03431Y0362*
X03436Y03624*
X03439Y03629*
X03441Y03636*
X03439Y03642*
X03436Y03647*
X03431Y03651*
X03424Y03652*
G37*
G36*
X02799Y03632D02*
X02793Y03631D01*
X02788Y03627*
X02784Y03622*
X02783Y03616*
X02784Y03609*
X02788Y03604*
X02793Y036*
X02799Y03599*
X02806Y036*
X02811Y03604*
X02814Y03609*
X02816Y03616*
X02814Y03622*
X02811Y03627*
X02806Y03631*
X02799Y03632*
G37*
G36*
X01884Y03617D02*
X01878Y03616D01*
X01873Y03612*
X01869Y03607*
X01868Y03601*
X01869Y03594*
X01873Y03589*
X01878Y03585*
X01884Y03584*
X01891Y03585*
X01896Y03589*
X01899Y03594*
X01901Y03601*
X01899Y03607*
X01896Y03612*
X01891Y03616*
X01884Y03617*
G37*
G36*
X03239Y03612D02*
X03233Y03611D01*
X03228Y03607*
X03224Y03602*
X03223Y03596*
X03224Y03589*
X03228Y03584*
X03233Y0358*
X03239Y03579*
X03246Y0358*
X03251Y03584*
X03254Y03589*
X03256Y03596*
X03254Y03602*
X03251Y03607*
X03246Y03611*
X03239Y03612*
G37*
G36*
X01549Y03637D02*
X01543Y03636D01*
X01538Y03632*
X01534Y03627*
X01533Y03621*
X01534Y03614*
X01538Y03609*
X01543Y03605*
X01549Y03604*
X01556Y03605*
X01556Y03606*
X01559Y03602*
X01559Y03602*
X01558Y03596*
X01559Y03589*
X01563Y03584*
X01568Y0358*
X01574Y03579*
X01581Y0358*
X01586Y03584*
X01589Y03589*
X01591Y03596*
X01589Y03602*
X01586Y03607*
X01581Y03611*
X01574Y03612*
X01568Y03611*
X01568Y0361*
X01564Y03614*
X01564Y03614*
X01566Y03621*
X01564Y03627*
X01561Y03632*
X01556Y03636*
X01549Y03637*
G37*
G36*
X0412Y0361D02*
X04114Y03609D01*
X04108Y03605*
X04105Y036*
X04104Y03594*
X04105Y03587*
X04108Y03582*
X04114Y03579*
X0412Y03577*
X04126Y03579*
X04131Y03582*
X04135Y03587*
X04136Y03594*
X04135Y036*
X04131Y03605*
X04126Y03609*
X0412Y0361*
G37*
G36*
X0144Y03573D02*
X01434Y03572D01*
X01429Y03568*
X01425Y03563*
X01424Y03557*
X01425Y0355*
X01429Y03545*
X01434Y03541*
X0144Y0354*
X01447Y03541*
X01452Y03545*
X01455Y0355*
X01457Y03557*
X01455Y03563*
X01452Y03568*
X01447Y03572*
X0144Y03573*
G37*
G36*
X02724Y03537D02*
X02718Y03536D01*
X02713Y03532*
X02709Y03527*
X02708Y03521*
X02709Y03514*
X02713Y03509*
X02718Y03505*
X02724Y03504*
X02731Y03505*
X02736Y03509*
X02739Y03514*
X02741Y03521*
X02739Y03527*
X02736Y03532*
X02731Y03536*
X02724Y03537*
G37*
G36*
X02674Y03517D02*
X02668Y03516D01*
X02663Y03512*
X02659Y03507*
X02658Y03501*
X02659Y03494*
X02663Y03489*
X02668Y03485*
X02674Y03484*
X02681Y03485*
X02686Y03489*
X02689Y03494*
X02691Y03501*
X02689Y03507*
X02686Y03512*
X02681Y03516*
X02674Y03517*
G37*
G36*
X03622Y03502D02*
X03616Y03501D01*
X03611Y03497*
X03607Y03492*
X03606Y03486*
X03607Y03479*
X03611Y03474*
X03616Y0347*
X03622Y03469*
X03629Y0347*
X03634Y03474*
X03637Y03479*
X03639Y03486*
X03637Y03492*
X03634Y03497*
X03629Y03501*
X03622Y03502*
G37*
G36*
X02579D02*
X02573Y03501D01*
X02568Y03497*
X02564Y03492*
X02563Y03486*
X02564Y03479*
X02568Y03474*
X02573Y0347*
X02579Y03469*
X02586Y0347*
X02591Y03474*
X02594Y03479*
X02596Y03486*
X02594Y03492*
X02591Y03497*
X02586Y03501*
X02579Y03502*
G37*
G36*
X03529Y03497D02*
X03523Y03496D01*
X03518Y03492*
X03514Y03487*
X03513Y03481*
X03514Y03474*
X03518Y03469*
X03523Y03465*
X03529Y03464*
X03536Y03465*
X03541Y03469*
X03544Y03474*
X03546Y03481*
X03544Y03487*
X03541Y03492*
X03536Y03496*
X03529Y03497*
G37*
G36*
X03436Y03473D02*
X0343Y03472D01*
X03425Y03468*
X03421Y03463*
X0342Y03457*
X03421Y0345*
X03425Y03445*
X0343Y03441*
X03436Y0344*
X03443Y03441*
X03448Y03445*
X0345Y03448*
X0345Y03448*
X03456Y03447*
X03458Y03444*
X03463Y0344*
X03469Y03439*
X03476Y0344*
X03481Y03444*
X03484Y03449*
X03486Y03456*
X03484Y03462*
X03481Y03467*
X03476Y03471*
X03469Y03472*
X03463Y03471*
X03458Y03467*
X03456Y03464*
X03456Y03464*
X0345Y03465*
X03448Y03468*
X03443Y03472*
X03436Y03473*
G37*
G36*
X03358Y03464D02*
X03352Y03463D01*
X03347Y03459*
X03343Y03454*
X03342Y03448*
X03343Y03441*
X03347Y03436*
X03352Y03432*
X03358Y03431*
X03365Y03432*
X0337Y03436*
X03373Y03441*
X03374Y03443*
X03379*
X03379Y0344*
X03383Y03435*
X03388Y03431*
X03394Y0343*
X03401Y03431*
X03406Y03435*
X03409Y0344*
X03411Y03447*
X03409Y03453*
X03406Y03458*
X03401Y03462*
X03394Y03463*
X03388Y03462*
X03383Y03458*
X03379Y03453*
X03379Y03451*
X03374*
X03373Y03454*
X0337Y03459*
X03365Y03463*
X03358Y03464*
G37*
G36*
X02634Y03422D02*
X02628Y03421D01*
X02623Y03417*
X02619Y03412*
X02618Y03406*
X02619Y03399*
X02623Y03394*
X02628Y0339*
X02634Y03389*
X02641Y0339*
X02646Y03394*
X02649Y03399*
X02651Y03406*
X02649Y03412*
X02646Y03417*
X02641Y03421*
X02634Y03422*
G37*
G36*
X03068Y03411D02*
X03062Y0341D01*
X03057Y03407*
X03053Y03401*
X03052Y03395*
X03053Y03389*
X03057Y03384*
X03062Y0338*
X03068Y03379*
X03075Y0338*
X0308Y03384*
X03083Y03389*
X03085Y03395*
X03083Y03401*
X0308Y03407*
X03075Y0341*
X03068Y03411*
G37*
G36*
X03302Y0336D02*
X03296Y03359D01*
X03291Y03355*
X03287Y0335*
X03286Y03344*
X03287Y03337*
X03291Y03332*
X03296Y03328*
X03302Y03327*
X03309Y03328*
X03314Y03332*
X03317Y03337*
X03319Y03344*
X03317Y0335*
X03314Y03355*
X03309Y03359*
X03302Y0336*
G37*
G36*
X03744Y03358D02*
X03738Y03357D01*
X03733Y03353*
X03729Y03348*
X03728Y03342*
X03729Y03335*
X03733Y0333*
X03738Y03326*
X03744Y03325*
X03751Y03326*
X03756Y0333*
X03759Y03335*
X03761Y03342*
X03759Y03348*
X03756Y03353*
X03751Y03357*
X03744Y03358*
G37*
G36*
X03542Y03335D02*
X03536Y03334D01*
X03531Y0333*
X03527Y03325*
X03526Y03319*
X03527Y03312*
X03531Y03307*
X03536Y03303*
X03542Y03302*
X03549Y03303*
X03554Y03307*
X03557Y03312*
X03559Y03319*
X03557Y03325*
X03554Y0333*
X03549Y03334*
X03542Y03335*
G37*
G36*
X03263Y0332D02*
X03257Y03318D01*
X03252Y03315*
X03248Y0331*
X03247Y03303*
X03248Y03297*
X03252Y03292*
X03257Y03288*
X03263Y03287*
X03269Y03288*
X03275Y03292*
X03278Y03297*
X0328Y03303*
X03278Y0331*
X03275Y03315*
X03269Y03318*
X03263Y0332*
G37*
G36*
X0333Y03317D02*
X03324Y03316D01*
X03319Y03312*
X03315Y03307*
X03314Y03301*
X03315Y03294*
X03319Y03289*
X03324Y03285*
X0333Y03284*
X03337Y03285*
X03342Y03289*
X03345Y03294*
X03347Y03301*
X03345Y03307*
X03342Y03312*
X03337Y03316*
X0333Y03317*
G37*
G36*
X03491Y03313D02*
X03485Y03312D01*
X0348Y03308*
X03476Y03303*
X03475Y03297*
X03476Y0329*
X0348Y03285*
X03485Y03281*
X03491Y0328*
X03498Y03281*
X03503Y03285*
X03506Y0329*
X03508Y03297*
X03506Y03303*
X03503Y03308*
X03498Y03312*
X03491Y03313*
G37*
G36*
X03653Y03309D02*
X03647Y03308D01*
X03642Y03304*
X03638Y03299*
X03637Y03293*
X03638Y03286*
X03642Y03281*
X03647Y03277*
X03653Y03276*
X0366Y03277*
X03665Y03281*
X03668Y03286*
X0367Y03293*
X03668Y03299*
X03665Y03304*
X0366Y03308*
X03653Y03309*
G37*
G36*
X03374Y03289D02*
X03368Y03288D01*
X03363Y03284*
X03359Y03279*
X03358Y03273*
X03359Y03266*
X03363Y03261*
X03368Y03257*
X03374Y03256*
X03381Y03257*
X03386Y03261*
X03389Y03266*
X03391Y03273*
X03389Y03279*
X03386Y03284*
X03381Y03288*
X03374Y03289*
G37*
G36*
X02559Y03309D02*
X0246D01*
Y03249*
X02559*
Y03266*
X02583*
X02588Y03267*
X02592Y0327*
X02594Y03272*
X02597Y03272*
X02602Y03276*
X02605Y03281*
X02607Y03288*
X02605Y03294*
X02602Y03299*
X02597Y03303*
X0259Y03304*
X02584Y03303*
X02579Y03299*
X02575Y03294*
X02575Y03291*
X02559*
Y03309*
G37*
G36*
X03744Y03277D02*
X03738Y03276D01*
X03733Y03272*
X03729Y03267*
X03728Y03261*
X03729Y03254*
X03733Y03249*
X03738Y03245*
X03744Y03244*
X03751Y03245*
X03756Y03249*
X03759Y03254*
X03761Y03261*
X03759Y03267*
X03756Y03272*
X03751Y03276*
X03744Y03277*
G37*
G36*
X0323Y03251D02*
X03224Y0325D01*
X03219Y03246*
X03215Y03241*
X03214Y03235*
X03215Y03228*
X03219Y03223*
X03224Y03219*
X0323Y03218*
X03237Y03219*
X03242Y03223*
X03245Y03228*
X03247Y03235*
X03245Y03241*
X03242Y03246*
X03237Y0325*
X0323Y03251*
G37*
G36*
X03806D02*
X038Y0325D01*
X03795Y03246*
X03791Y03241*
X0379Y03235*
X03791Y03228*
X03795Y03223*
X03797Y03222*
X03796Y03216*
X03793Y03216*
X03788Y03212*
X03784Y03207*
X03783Y03201*
X03784Y03194*
X03788Y03189*
X03793Y03185*
X03799Y03184*
X03806Y03185*
X03811Y03189*
X03814Y03194*
X03816Y03201*
X03814Y03207*
X03811Y03212*
X03809Y03214*
X0381Y03219*
X03813Y03219*
X03818Y03223*
X03821Y03228*
X03823Y03235*
X03821Y03241*
X03818Y03246*
X03813Y0325*
X03806Y03251*
G37*
G36*
X03188Y03203D02*
X03182Y03202D01*
X03177Y03198*
X03173Y03193*
X03172Y03187*
X03173Y0318*
X03177Y03175*
X03182Y03171*
X03188Y0317*
X03195Y03171*
X032Y03175*
X03204Y0318*
X03205Y03187*
X03204Y03193*
X032Y03198*
X03195Y03202*
X03188Y03203*
G37*
G36*
X01459Y03163D02*
X01453Y03162D01*
X01448Y03158*
X01444Y03153*
X01443Y03147*
X01444Y0314*
X01448Y03135*
X01453Y03131*
X01459Y0313*
X01466Y03131*
X01471Y03135*
X01474Y0314*
X01476Y03147*
X01474Y03153*
X01471Y03158*
X01466Y03162*
X01459Y03163*
G37*
G36*
X03275Y03158D02*
X03269Y03156D01*
X03264Y03153*
X0326Y03147*
X03259Y03141*
X0326Y03135*
X03264Y0313*
X03269Y03126*
X03275Y03125*
X03281Y03126*
X03287Y0313*
X0329Y03135*
X03291Y03141*
X0329Y03147*
X03287Y03153*
X03281Y03156*
X03275Y03158*
G37*
G36*
X03183Y03152D02*
X03176Y0315D01*
X03171Y03147*
X03168Y03142*
X03166Y03135*
X03168Y03129*
X03171Y03124*
X03176Y0312*
X03183Y03119*
X03189Y0312*
X03194Y03124*
X03198Y03129*
X03199Y03135*
X03198Y03142*
X03194Y03147*
X03189Y0315*
X03183Y03152*
G37*
G36*
X02559Y0323D02*
X0246D01*
Y03188*
X02456Y03187*
X0245Y03183*
X02447Y03178*
X02446Y03172*
X02447Y03166*
X0245Y0316*
X02456Y03157*
X02459Y03156*
X0246Y03151*
Y03151*
Y03091*
X02559*
Y03134*
X02595Y0317*
X02598Y03171*
X02603Y03174*
X02606Y03179*
X02608Y03186*
X02606Y03192*
X02603Y03197*
X02598Y03201*
X02591Y03202*
X02585Y03201*
X0258Y03197*
X02576Y03192*
X02575Y03186*
X02575Y03185*
X02564Y03173*
X02559Y03176*
Y0323*
G37*
G36*
X03491Y03119D02*
X03485Y03118D01*
X0348Y03114*
X03476Y03109*
X03475Y03103*
X03476Y03096*
X0348Y03091*
X03485Y03087*
X03491Y03086*
X03498Y03087*
X03503Y03091*
X03506Y03096*
X03508Y03103*
X03506Y03109*
X03503Y03114*
X03498Y03118*
X03491Y03119*
G37*
G36*
X03717Y03088D02*
X03711Y03087D01*
X03706Y03083*
X03702Y03078*
X03701Y03072*
X03702Y03065*
X03706Y0306*
X03711Y03056*
X03717Y03055*
X03724Y03056*
X03729Y0306*
X03732Y03065*
X03734Y03072*
X03732Y03078*
X03729Y03083*
X03724Y03087*
X03717Y03088*
G37*
G36*
X03368Y03066D02*
X03362Y03065D01*
X03357Y03061*
X03353Y03056*
X03352Y0305*
X03353Y03043*
X03357Y03038*
X03362Y03034*
X03368Y03033*
X03375Y03034*
X0338Y03038*
X03383Y03043*
X03385Y0305*
X03383Y03056*
X0338Y03061*
X03375Y03065*
X03368Y03066*
G37*
G36*
X03344Y03012D02*
X03338Y03011D01*
X03333Y03007*
X03329Y03002*
X03328Y02996*
X03329Y02989*
X03333Y02984*
X03338Y0298*
X03344Y02979*
X03351Y0298*
X03356Y02984*
X03359Y02989*
X03361Y02996*
X03359Y03002*
X03356Y03007*
X03351Y03011*
X03344Y03012*
G37*
G36*
X02473Y02996D02*
X02467Y02995D01*
X02464Y02993*
X02434*
X02429Y02992*
X02424Y02989*
X02416Y0298*
X02415*
X02414Y0298*
X02367*
Y02907*
X02428*
Y02956*
X02431Y02958*
X02439Y02966*
X02464*
X02467Y02964*
X02473Y02963*
X0248Y02964*
X02485Y02968*
X02488Y02973*
X0249Y0298*
X02488Y02986*
X02485Y02991*
X0248Y02995*
X02473Y02996*
G37*
G36*
X03197Y02986D02*
X03191Y02985D01*
X03186Y02981*
X03182Y02976*
X03181Y0297*
X03182Y02963*
X03186Y02958*
X03191Y02954*
X03197Y02953*
X03204Y02954*
X03209Y02958*
X03212Y02963*
X03214Y0297*
X03212Y02976*
X03209Y02981*
X03204Y02985*
X03197Y02986*
G37*
G36*
X03277Y02979D02*
X03271Y02978D01*
X03266Y02975*
X03262Y02969*
X03261Y02963*
X03262Y02957*
X03266Y02952*
X03271Y02948*
X03277Y02947*
X03283Y02948*
X03289Y02952*
X03292Y02957*
X03293Y02963*
X03292Y02969*
X03289Y02975*
X03283Y02978*
X03277Y02979*
G37*
G36*
X0337Y02904D02*
X03364Y02903D01*
X03359Y02899*
X03355Y02894*
X03354Y02888*
X03355Y02881*
X03359Y02876*
X03364Y02872*
X0337Y02871*
X03377Y02872*
X03382Y02876*
X03385Y02881*
X03387Y02888*
X03385Y02894*
X03382Y02899*
X03377Y02903*
X0337Y02904*
G37*
G36*
X02692Y02737D02*
X02686Y02736D01*
X02681Y02732*
X02677Y02727*
X02676Y02721*
X02677Y02715*
X02681Y02709*
X02686Y02706*
X02692Y02705*
X02699Y02706*
X02704Y02709*
X02707Y02715*
X02709Y02721*
X02707Y02727*
X02704Y02732*
X02699Y02736*
X02692Y02737*
G37*
G36*
X02394Y02736D02*
X02388Y02735D01*
X02383Y02732*
X02379Y02726*
X02378Y0272*
X02379Y02714*
X02383Y02708*
X02388Y02705*
X02394Y02704*
X024Y02705*
X02406Y02708*
X02409Y02714*
X02411Y0272*
X02409Y02726*
X02406Y02732*
X024Y02735*
X02394Y02736*
G37*
G36*
X02494Y02712D02*
X02488Y02711D01*
X02483Y02707*
X02479Y02702*
X02478Y02696*
X02479Y02689*
X02483Y02684*
X02488Y02681*
X02488Y02679*
Y02678*
X02488Y02675*
X02483Y02672*
X02479Y02667*
X02478Y02661*
X02479Y02654*
X02483Y02649*
X02488Y02645*
X02494Y02644*
X02501Y02645*
X02506Y02649*
X02509Y02654*
X02511Y02661*
X02509Y02667*
X02506Y02672*
X02501Y02675*
X02501Y02678*
Y02679*
X02501Y02681*
X02506Y02684*
X02509Y02689*
X02511Y02696*
X02509Y02702*
X02506Y02707*
X02501Y02711*
X02494Y02712*
G37*
G36*
X02958Y02637D02*
X02952Y02636D01*
X02947Y02632*
X02943Y02627*
X02942Y02621*
X02943Y02614*
X02947Y02609*
X02952Y02605*
X02958Y02604*
X02965Y02605*
X0297Y02609*
X02973Y02614*
X02975Y02621*
X02973Y02627*
X0297Y02632*
X02965Y02636*
X02958Y02637*
G37*
G36*
X02429D02*
X02422Y02636D01*
X02417Y02632*
X02414Y02627*
X02412Y02621*
X02414Y02614*
X02417Y02609*
X02422Y02605*
X02429Y02604*
X02435Y02605*
X0244Y02609*
X02444Y02614*
X02445Y02621*
X02444Y02627*
X0244Y02632*
X02435Y02636*
X02429Y02637*
G37*
G36*
X02252Y02629D02*
X02246Y02628D01*
X0224Y02625*
X02237Y02619*
X02236Y02613*
X02237Y02607*
X02239Y02603*
X02236Y02599*
X02231Y026*
X02225Y02599*
X0222Y02595*
X02216Y0259*
X02215Y02584*
X02216Y02577*
X0222Y02572*
X02225Y02569*
X02231Y02567*
X02237Y02569*
X02243Y02572*
X02246Y02577*
X02248Y02584*
X02246Y0259*
X02244Y02594*
X02247Y02598*
X02252Y02597*
X02258Y02598*
X02263Y02602*
X02267Y02607*
X02268Y02613*
X02267Y02619*
X02263Y02625*
X02258Y02628*
X02252Y02629*
G37*
G36*
X02821Y02617D02*
X02815Y02616D01*
X0281Y02612*
X02806Y02607*
X02805Y02601*
X02806Y02594*
X0281Y02589*
X02815Y02585*
X02821Y02584*
X02828Y02585*
X02833Y02589*
X02836Y02594*
X02838Y02601*
X02836Y02607*
X02833Y02612*
X02828Y02616*
X02821Y02617*
G37*
G36*
X03623Y02603D02*
X03617Y02602D01*
X03612Y02598*
X03608Y02593*
X03607Y02587*
X03608Y0258*
X03612Y02575*
X03617Y02571*
X03623Y0257*
X0363Y02571*
X03635Y02575*
X03638Y0258*
X0364Y02587*
X03638Y02593*
X03635Y02598*
X0363Y02602*
X03623Y02603*
G37*
G36*
X02321Y02602D02*
X02315Y02601D01*
X0231Y02597*
X02306Y02592*
X02305Y02586*
X02306Y02579*
X0231Y02574*
X02315Y0257*
X02321Y02569*
X02327Y0257*
X02333Y02574*
X02336Y02579*
X02337Y02586*
X02336Y02592*
X02333Y02597*
X02327Y02601*
X02321Y02602*
G37*
G36*
X02409Y02595D02*
X02403Y02594D01*
X02398Y0259*
X02394Y02585*
X02393Y02579*
X02394Y02572*
X02398Y02567*
X02403Y02563*
X02409Y02562*
X02416Y02563*
X02421Y02567*
X02424Y02572*
X02426Y02579*
X02424Y02585*
X02421Y0259*
X02416Y02594*
X02409Y02595*
G37*
G36*
X02586Y02585D02*
X0258Y02584D01*
X02575Y0258*
X02571Y02575*
X0257Y02569*
X02571Y02562*
X02575Y02557*
X0258Y02553*
X02586Y02552*
X02593Y02553*
X02598Y02557*
X02601Y02562*
X02603Y02569*
X02601Y02575*
X02598Y0258*
X02593Y02584*
X02586Y02585*
G37*
G36*
X02783Y02584D02*
X02777Y02583D01*
X02772Y02579*
X02768Y02574*
X02767Y02568*
X02768Y02561*
X02772Y02556*
X02777Y02552*
X02783Y02551*
X0279Y02552*
X02795Y02556*
X02798Y02561*
X028Y02568*
X02798Y02574*
X02795Y02579*
X0279Y02583*
X02783Y02584*
G37*
G36*
X02685D02*
X02679Y02583D01*
X02674Y02579*
X0267Y02574*
X02669Y02568*
X0267Y02561*
X02674Y02556*
X02679Y02552*
X02685Y02551*
X02692Y02552*
X02697Y02556*
X027Y02561*
X02702Y02568*
X027Y02574*
X02697Y02579*
X02692Y02583*
X02685Y02584*
G37*
G36*
X02881Y02582D02*
X02875Y02581D01*
X0287Y02577*
X02866Y02572*
X02865Y02566*
X02866Y02559*
X0287Y02554*
X02875Y0255*
X02881Y02549*
X02888Y0255*
X02893Y02554*
X02896Y02559*
X02898Y02566*
X02896Y02572*
X02893Y02577*
X02888Y02581*
X02881Y02582*
G37*
G36*
X02624Y02477D02*
X02618Y02476D01*
X02613Y02472*
X02609Y02467*
X02608Y02461*
X02609Y02454*
X02609Y02454*
X02606Y0245*
X02606Y02451*
X02599Y02452*
X02593Y02451*
X02588Y02447*
X02584Y02442*
X02583Y02436*
X02584Y02431*
X02583Y0243*
X02581Y02427*
X0258Y02427*
X02575Y02428*
X02569Y02427*
X02564Y02423*
X0256Y02418*
X02559Y02412*
X0256Y02405*
X02564Y024*
X02569Y02396*
X02575Y02395*
X02582Y02396*
X02587Y024*
X0259Y02405*
X02592Y02412*
X02591Y02416*
X02591Y02417*
X02594Y0242*
X02595Y0242*
X02599Y02419*
X02606Y0242*
X02611Y02424*
X02614Y02429*
X02616Y02436*
X02614Y02442*
X02614Y02442*
X02618Y02446*
X02618Y02445*
X02624Y02444*
X02631Y02445*
X02636Y02449*
X02639Y02454*
X02641Y02461*
X02639Y02467*
X02636Y02472*
X02631Y02476*
X02624Y02477*
G37*
G36*
X02272Y0248D02*
X02265Y02478D01*
X0226Y02475*
X02256Y0247*
X02255Y02463*
X02256Y02457*
X0226Y02452*
X02265Y02448*
X02272Y02447*
X02278Y02448*
X02283Y02452*
X02287Y02457*
X02288Y02463*
X02287Y0247*
X02283Y02475*
X02278Y02478*
X02272Y0248*
G37*
G36*
X02525Y02479D02*
X02519Y02478D01*
X02514Y02474*
X0251Y02469*
X02509Y02463*
X0251Y02456*
X02514Y02451*
X02519Y02447*
X02525Y02446*
X02532Y02447*
X02537Y02451*
X0254Y02456*
X02542Y02463*
X0254Y02469*
X02537Y02474*
X02532Y02478*
X02525Y02479*
G37*
G36*
X02948Y02472D02*
X02942Y02471D01*
X02937Y02467*
X02933Y02462*
X02932Y02456*
X02933Y02449*
X02937Y02444*
X02942Y0244*
X02948Y02439*
X02955Y0244*
X0296Y02444*
X02963Y02449*
X02965Y02456*
X02963Y02462*
X0296Y02467*
X02955Y02471*
X02948Y02472*
G37*
G36*
X02475D02*
X02469Y02471D01*
X02464Y02467*
X0246Y02462*
X02459Y02456*
X0246Y02449*
X02464Y02444*
X02469Y0244*
X02475Y02439*
X02482Y0244*
X02487Y02444*
X0249Y02449*
X02492Y02456*
X0249Y02462*
X02487Y02467*
X02482Y02471*
X02475Y02472*
G37*
G36*
X0299Y02457D02*
X02983Y02456D01*
X02976Y02452*
X02972Y02445*
X02971Y02438*
X02972Y02431*
X02976Y02424*
X02983Y0242*
X0299Y02419*
X02997Y0242*
X03004Y02424*
X03008Y02431*
X03009Y02438*
X03008Y02445*
X03004Y02452*
X02997Y02456*
X0299Y02457*
G37*
G36*
X02203D02*
X02195Y02456D01*
X02189Y02452*
X02185Y02445*
X02183Y02438*
X02185Y02431*
X02189Y02424*
X02195Y0242*
X02203Y02419*
X0221Y0242*
X02216Y02424*
X0222Y02431*
X02222Y02438*
X0222Y02445*
X02216Y02452*
X0221Y02456*
X02203Y02457*
G37*
G36*
X03617Y02553D02*
X03604Y02552D01*
X03592Y02548*
X0358Y02542*
X0357Y02533*
X03561Y02523*
X03555Y02512*
X03551Y02499*
X0355Y02486*
X03551Y02473*
X03555Y0246*
X03561Y02448*
X0357Y02438*
X0358Y0243*
X03592Y02424*
X03604Y0242*
X03617Y02418*
X03631Y0242*
X03643Y02424*
X03655Y0243*
X03665Y02438*
X03673Y02448*
X0368Y0246*
X03684Y02473*
X03685Y02486*
X03684Y02499*
X0368Y02512*
X03673Y02523*
X03665Y02533*
X03655Y02542*
X03643Y02548*
X03631Y02552*
X03617Y02553*
G37*
G36*
X02783Y02445D02*
X02777Y02444D01*
X02772Y0244*
X02768Y02435*
X02767Y02429*
X02768Y02422*
X02772Y02417*
X02777Y02413*
X02783Y02412*
X0279Y02413*
X02795Y02417*
X02798Y02422*
X028Y02429*
X02798Y02435*
X02795Y0244*
X0279Y02444*
X02783Y02445*
G37*
G36*
X02894Y02447D02*
X02888Y02446D01*
X02883Y02442*
X02879Y02437*
X02878Y02431*
X02879Y02424*
X02883Y02419*
X02888Y02415*
X02894Y02414*
X02901Y02415*
X02902Y02417*
X02909Y02416*
X02914Y02412*
X0292Y02411*
X02927Y02412*
X02932Y02416*
X02935Y02421*
X02937Y02428*
X02935Y02434*
X02932Y02439*
X02927Y02443*
X0292Y02444*
X02914Y02443*
X02909Y02439*
X02908*
X02906Y02442*
X02901Y02446*
X02894Y02447*
G37*
G36*
X02488Y02429D02*
X02482Y02428D01*
X02477Y02424*
X02473Y02419*
X02472Y02413*
X02473Y02406*
X02477Y02401*
X02482Y02397*
X02488Y02396*
X02495Y02397*
X025Y02401*
X02503Y02406*
X02505Y02413*
X02503Y02419*
X025Y02424*
X02495Y02428*
X02488Y02429*
G37*
G36*
X02404Y02428D02*
X02398Y02427D01*
X02393Y02423*
X02389Y02418*
X02388Y02412*
X02389Y02405*
X02393Y024*
X02398Y02396*
X02404Y02395*
X02411Y02396*
X02416Y024*
X02419Y02405*
X02421Y02412*
X02419Y02418*
X02416Y02423*
X02411Y02427*
X02404Y02428*
G37*
G36*
X03498Y02357D02*
X03492Y02356D01*
X03487Y02352*
X03483Y02347*
X03482Y02341*
X03483Y02334*
X03487Y02329*
X03492Y02325*
X03498Y02324*
X03505Y02325*
X0351Y02329*
X03513Y02334*
X03515Y02341*
X03513Y02347*
X0351Y02352*
X03505Y02356*
X03498Y02357*
G37*
G36*
X02475Y02307D02*
X02469Y02306D01*
X02464Y02302*
X0246Y02297*
X02455Y02297*
X0245Y02298*
X02444Y02297*
X02439Y02293*
X02435Y02288*
X02434Y02282*
X02435Y02275*
X02439Y0227*
X02444Y02266*
X0245Y02265*
X02457Y02266*
X02462Y0227*
X02465Y02275*
X0247Y02275*
X02475Y02274*
X02482Y02275*
X02487Y02279*
X0249Y02284*
X02492Y02291*
X0249Y02297*
X02487Y02302*
X02482Y02306*
X02475Y02307*
G37*
G36*
X02803Y02323D02*
X02797Y02322D01*
X02792Y02318*
X02788Y02313*
X02787Y02307*
X02788Y023*
X02792Y02295*
X02797Y02291*
X02803Y0229*
X0281Y02291*
X02815Y02295*
X02818Y023*
X0282Y02307*
X02818Y02313*
X02815Y02318*
X0281Y02322*
X02803Y02323*
G37*
G36*
X02685Y02327D02*
X02679Y02326D01*
X02674Y02322*
X0267Y02317*
X02669Y02311*
X02668Y0231*
X02666Y02308*
X02665Y02307*
X02659Y02306*
X02654Y02302*
X0265Y02297*
X02649Y02291*
X02648Y02289*
X02645Y0229*
X02639Y02289*
X02634Y02285*
X0263Y0228*
X02629Y02274*
X0263Y02267*
X02634Y02262*
X02639Y02258*
X02645Y02257*
X02652Y02258*
X02657Y02262*
X0266Y02267*
X02662Y02274*
X02663Y02275*
X02665Y02274*
X02672Y02275*
X02677Y02279*
X0268Y02284*
X02681Y02289*
X02686Y02289*
X02687Y02282*
X02691Y02277*
X02696Y02273*
X02702Y02272*
X02709Y02273*
X02714Y02277*
X02716Y0228*
X0272Y02277*
X02726Y02276*
X02733Y02277*
X02738Y02281*
X02741Y02286*
X02743Y02293*
X02741Y02299*
X02738Y02304*
X02733Y02308*
X02726Y02309*
X0272Y02308*
X02715Y02304*
X02713Y02301*
X02709Y02304*
X02706Y02304*
X02701Y02309*
X02702Y02311*
X027Y02317*
X02697Y02322*
X02692Y02326*
X02685Y02327*
G37*
G36*
X02871Y02313D02*
X02865Y02312D01*
X0286Y02308*
X02856Y02303*
X02855Y02297*
X02856Y0229*
X0286Y02285*
X02865Y02281*
X02871Y0228*
X02878Y02281*
X02883Y02285*
X02886Y0229*
X02888Y02297*
X02886Y02303*
X02883Y02308*
X02878Y02312*
X02871Y02313*
G37*
G36*
X02985Y02303D02*
X02979Y02302D01*
X02974Y02298*
X0297Y02293*
X02969Y02287*
X0297Y0228*
X02974Y02275*
X02979Y02271*
X02985Y0227*
X02992Y02271*
X02997Y02275*
X03Y0228*
X03002Y02287*
X03Y02293*
X02997Y02298*
X02992Y02302*
X02985Y02303*
G37*
G36*
X02942Y02302D02*
X02936Y02301D01*
X02931Y02297*
X02927Y02292*
X02926Y02286*
X02927Y02279*
X02931Y02274*
X02936Y0227*
X02942Y02269*
X02949Y0227*
X02954Y02274*
X02957Y02279*
X02959Y02286*
X02957Y02292*
X02954Y02297*
X02949Y02301*
X02942Y02302*
G37*
G36*
X02409Y0233D02*
X02403Y02329D01*
X02398Y02325*
X02394Y0232*
X02393Y02314*
X02394Y02307*
X02398Y02302*
X02399Y02301*
Y02295*
X02398Y02294*
X02394Y02289*
X02393Y02283*
X02394Y02276*
X02398Y02271*
X02403Y02267*
X02409Y02266*
X02416Y02267*
X02421Y02271*
X02424Y02276*
X02426Y02283*
X02424Y02289*
X02421Y02294*
X02419Y02295*
Y02301*
X02421Y02302*
X02424Y02307*
X02426Y02314*
X02424Y0232*
X02421Y02325*
X02416Y02329*
X02409Y0233*
G37*
G36*
X02581Y02324D02*
X02575Y02323D01*
X0257Y02319*
X02566Y02314*
X02565Y02308*
X02566Y02301*
X02568Y02298*
X02568Y02292*
X02564Y02287*
X02563Y02281*
X02564Y02274*
X02568Y02269*
X02573Y02265*
X02579Y02264*
X02586Y02265*
X02591Y02269*
X02594Y02274*
X02596Y02281*
X02594Y02287*
X02592Y0229*
X02593Y02296*
X02596Y02301*
X02598Y02308*
X02596Y02314*
X02593Y02319*
X02588Y02323*
X02581Y02324*
G37*
G36*
X02253Y02295D02*
X02247Y02294D01*
X02242Y0229*
X02238Y02285*
X02237Y02279*
X02238Y02272*
X02242Y02267*
X02247Y02263*
X02253Y02262*
X0226Y02263*
X02265Y02267*
X02268Y02272*
X0227Y02279*
X02268Y02285*
X02265Y0229*
X0226Y02294*
X02253Y02295*
G37*
G36*
X03342Y02279D02*
X03336Y02278D01*
X03331Y02274*
X03327Y02269*
X03326Y02263*
X03327Y02256*
X03331Y02251*
X03336Y02247*
X03342Y02246*
X03349Y02247*
X03354Y02251*
X03357Y02256*
X03359Y02263*
X03357Y02269*
X03354Y02274*
X03349Y02278*
X03342Y02279*
G37*
G36*
X02841D02*
X02835Y02278D01*
X0283Y02274*
X02826Y02269*
X02825Y02263*
X02826Y02256*
X0283Y02251*
X02835Y02247*
X02841Y02246*
X02848Y02247*
X02853Y02251*
X02856Y02256*
X02858Y02263*
X02856Y02269*
X02853Y02274*
X02848Y02278*
X02841Y02279*
G37*
G36*
X02499Y02252D02*
X02493Y02251D01*
X02488Y02247*
X02484Y02242*
X02483Y02236*
X02484Y02229*
X02488Y02224*
X02493Y0222*
X02499Y02219*
X02506Y0222*
X02511Y02224*
X02514Y02229*
X02516Y02236*
X02514Y02242*
X02511Y02247*
X02506Y02251*
X02499Y02252*
G37*
G36*
X0233Y02231D02*
X02324Y0223D01*
X02319Y02226*
X02315Y02221*
X02314Y02215*
X02315Y02208*
X02319Y02203*
X02324Y02199*
X0233Y02198*
X02337Y02199*
X02342Y02203*
X02345Y02208*
X02347Y02215*
X02345Y02221*
X02342Y02226*
X02337Y0223*
X0233Y02231*
G37*
G36*
X03571Y02116D02*
X03564Y02114D01*
X03558Y0211*
X03554Y02104*
X03552Y02097*
X03554Y02089*
X03558Y02083*
X03564Y02079*
X03571Y02077*
X03579Y02079*
X03585Y02083*
X03589Y02089*
X0359Y02097*
X03589Y02104*
X03585Y0211*
X03579Y02114*
X03571Y02116*
G37*
G36*
X03719Y02012D02*
X03713Y02011D01*
X03708Y02007*
X03704Y02002*
X03703Y01996*
X03704Y01989*
X03708Y01984*
X03713Y0198*
X03719Y01979*
X03726Y0198*
X03731Y01984*
X03734Y01989*
X03736Y01996*
X03734Y02002*
X03731Y02007*
X03726Y02011*
X03719Y02012*
G37*
G36*
X03554Y02007D02*
X03548Y02006D01*
X03543Y02002*
X03539Y01997*
X03538Y01991*
X03539Y01984*
X03543Y01979*
X03548Y01975*
X03554Y01974*
X03561Y01975*
X03566Y01979*
X03569Y01984*
X03571Y01991*
X03569Y01997*
X03566Y02002*
X03561Y02006*
X03554Y02007*
G37*
G36*
X03298Y01987D02*
X03292Y01986D01*
X03287Y01982*
X03283Y01977*
X03282Y01971*
X03283Y01964*
X03287Y01959*
X03292Y01955*
X03298Y01954*
X03305Y01955*
X0331Y01959*
X03313Y01964*
X03315Y01971*
X03313Y01977*
X0331Y01982*
X03305Y01986*
X03298Y01987*
G37*
G36*
X03554Y01957D02*
X03548Y01956D01*
X03543Y01952*
X03539Y01947*
X03538Y01941*
X03539Y01934*
X03543Y01929*
X03548Y01925*
X03554Y01924*
X03561Y01925*
X03566Y01929*
X03569Y01934*
X03571Y01941*
X03569Y01947*
X03566Y01952*
X03561Y01956*
X03554Y01957*
G37*
G36*
X03719Y01937D02*
X03713Y01936D01*
X03708Y01932*
X03704Y01927*
X03703Y01921*
X03704Y01914*
X03708Y01909*
X03713Y01905*
X03719Y01904*
X03726Y01905*
X03731Y01909*
X03734Y01914*
X03736Y01921*
X03734Y01927*
X03731Y01932*
X03726Y01936*
X03719Y01937*
G37*
G36*
X03554Y01907D02*
X03548Y01906D01*
X03543Y01902*
X03539Y01897*
X03538Y01891*
X03539Y01884*
X03543Y01879*
X03548Y01875*
X03554Y01874*
X03561Y01875*
X03566Y01879*
X03569Y01884*
X03571Y01891*
X03569Y01897*
X03566Y01902*
X03561Y01906*
X03554Y01907*
G37*
G36*
X03392Y01887D02*
X03386Y01886D01*
X03381Y01882*
X03377Y01877*
X03376Y01871*
X03377Y01864*
X03381Y01859*
X03386Y01855*
X03392Y01854*
X03399Y01855*
X03404Y01859*
X03407Y01864*
X03409Y01871*
X03407Y01877*
X03404Y01882*
X03399Y01886*
X03392Y01887*
G37*
G36*
X03439Y01887D02*
X03433Y01886D01*
X03427Y01882*
X03424Y01877*
X03422Y0187*
X03424Y01864*
X03427Y01859*
X03433Y01855*
X03439Y01854*
X03445Y01855*
X0345Y01859*
X03454Y01864*
X03455Y0187*
X03454Y01877*
X0345Y01882*
X03445Y01886*
X03439Y01887*
G37*
G36*
X03554Y01857D02*
X03548Y01856D01*
X03543Y01852*
X03539Y01847*
X03538Y01841*
X03539Y01834*
X03543Y01829*
X03548Y01825*
X03554Y01824*
X03561Y01825*
X03566Y01829*
X03569Y01834*
X03571Y01841*
X03569Y01847*
X03566Y01852*
X03561Y01856*
X03554Y01857*
G37*
G36*
X03804Y01856D02*
X03798Y01855D01*
X03793Y01851*
X03789Y01846*
X03788Y0184*
X03789Y01833*
X03793Y01828*
X03798Y01824*
X03804Y01823*
X03811Y01824*
X03816Y01828*
X03819Y01833*
X03821Y0184*
X03819Y01846*
X03816Y01851*
X03811Y01855*
X03804Y01856*
G37*
G36*
X06685Y01844D02*
X06679Y01843D01*
X06674Y01839*
X0667Y01834*
X06669Y01828*
X0667Y01821*
X06674Y01816*
X06679Y01812*
X06685Y01811*
X06692Y01812*
X06697Y01816*
X067Y01821*
X06702Y01828*
X067Y01834*
X06697Y01839*
X06692Y01843*
X06685Y01844*
G37*
G36*
X03329Y01842D02*
X03322Y01841D01*
X03317Y01837*
X03314Y01832*
X03312Y01826*
X03314Y01819*
X03317Y01814*
X03322Y0181*
X03329Y01809*
X03335Y0181*
X0334Y01814*
X03344Y01819*
X03345Y01826*
X03344Y01832*
X0334Y01837*
X03335Y01841*
X03329Y01842*
G37*
G36*
X03944Y01832D02*
X03938Y01831D01*
X03933Y01827*
X03929Y01822*
X03928Y01816*
X03929Y01809*
X03933Y01804*
X03938Y018*
X03944Y01799*
X03951Y018*
X03956Y01804*
X03959Y01809*
X03961Y01816*
X03959Y01822*
X03956Y01827*
X03951Y01831*
X03944Y01832*
G37*
G36*
X03056Y01828D02*
X0305Y01826D01*
X03045Y01823*
X03041Y01818*
X0304Y01811*
X03041Y01805*
X03045Y018*
X0305Y01796*
X03056Y01795*
X03063Y01796*
X03068Y018*
X03071Y01805*
X03073Y01811*
X03071Y01818*
X03068Y01823*
X03063Y01826*
X03056Y01828*
G37*
G36*
X03414Y01821D02*
X03408Y0182D01*
X03402Y01816*
X03399Y01811*
X03398Y01805*
X03399Y01798*
X03402Y01793*
X03408Y01789*
X03414Y01788*
X0342Y01789*
X03426Y01793*
X03429Y01798*
X0343Y01805*
X03429Y01811*
X03426Y01816*
X0342Y0182*
X03414Y01821*
G37*
G36*
X04064Y01812D02*
X04058Y01811D01*
X04053Y01807*
X04049Y01802*
X04048Y01796*
X04049Y01789*
X04053Y01784*
X04058Y0178*
X04064Y01779*
X04071Y0178*
X04076Y01784*
X04079Y01789*
X04081Y01796*
X04079Y01802*
X04076Y01807*
X04071Y01811*
X04064Y01812*
G37*
G36*
X06601Y01793D02*
X06595Y01792D01*
X0659Y01788*
X06586Y01783*
X06585Y01777*
X06586Y0177*
X0659Y01765*
X06595Y01761*
X06601Y0176*
X06608Y01761*
X06613Y01765*
X06616Y0177*
X06618Y01777*
X06616Y01783*
X06613Y01788*
X06608Y01792*
X06601Y01793*
G37*
G36*
X03719Y01782D02*
X03713Y01781D01*
X03708Y01777*
X03704Y01772*
X03703Y01766*
X03704Y01759*
X03708Y01754*
X03713Y0175*
X03719Y01749*
X03726Y0175*
X03731Y01754*
X03734Y01759*
X03736Y01766*
X03734Y01772*
X03731Y01777*
X03726Y01781*
X03719Y01782*
G37*
G36*
X04134Y01767D02*
X04128Y01766D01*
X04123Y01762*
X04119Y01757*
X04118Y01751*
X04119Y01744*
X04123Y01739*
X04128Y01735*
X04134Y01734*
X04141Y01735*
X04146Y01739*
X04149Y01744*
X04151Y01751*
X04149Y01757*
X04146Y01762*
X04141Y01766*
X04134Y01767*
G37*
G36*
X06602Y01738D02*
X06596Y01737D01*
X06591Y01733*
X06587Y01728*
X06586Y01722*
X06587Y01715*
X06591Y0171*
X06596Y01706*
X06602Y01705*
X06609Y01706*
X06614Y0171*
X06617Y01715*
X06619Y01722*
X06617Y01728*
X06614Y01733*
X06609Y01737*
X06602Y01738*
G37*
G36*
X03197Y0173D02*
X03191Y01729D01*
X03185Y01725*
X03182Y0172*
X0318Y01714*
X03182Y01707*
X03185Y01702*
X03191Y01698*
X03197Y01697*
X03203Y01698*
X03208Y01702*
X03212Y01707*
X03213Y01714*
X03212Y0172*
X03208Y01725*
X03203Y01729*
X03197Y0173*
G37*
G36*
X0341Y01729D02*
X03404Y01728D01*
X03399Y01725*
X03395Y01719*
X03394Y01713*
X03395Y01707*
X03399Y01702*
X03404Y01698*
X0341Y01697*
X03417Y01698*
X03422Y01702*
X03425Y01707*
X03427Y01713*
X03425Y01719*
X03422Y01725*
X03417Y01728*
X0341Y01729*
G37*
G36*
X03718Y01729D02*
X03712Y01728D01*
X03707Y01724*
X03703Y01719*
X03702Y01713*
X03703Y01706*
X03707Y01701*
X03712Y01697*
X03718Y01696*
X03725Y01697*
X0373Y01701*
X03733Y01706*
X03735Y01713*
X03733Y01719*
X0373Y01724*
X03725Y01728*
X03718Y01729*
G37*
G36*
X03996Y01727D02*
X0399Y01726D01*
X03985Y01722*
X03981Y01717*
X0398Y01711*
X03981Y01704*
X03985Y01699*
X0399Y01695*
X03996Y01694*
X04003Y01695*
X04008Y01699*
X04011Y01704*
X04013Y01711*
X04011Y01717*
X04008Y01722*
X04003Y01726*
X03996Y01727*
G37*
G36*
X03589D02*
X03583Y01726D01*
X03578Y01722*
X03574Y01717*
X03573Y01711*
X03574Y01704*
X03578Y01699*
X03583Y01695*
X03589Y01694*
X03596Y01695*
X03601Y01699*
X03604Y01704*
X03606Y01711*
X03604Y01717*
X03601Y01722*
X03596Y01726*
X03589Y01727*
G37*
G36*
X03803Y01707D02*
X03797Y01706D01*
X03792Y01702*
X03788Y01697*
X03787Y01691*
X03788Y01684*
X03792Y01679*
X03797Y01675*
X03803Y01674*
X0381Y01675*
X03815Y01679*
X03818Y01684*
X0382Y01691*
X03818Y01697*
X03815Y01702*
X0381Y01706*
X03803Y01707*
G37*
G36*
X03724Y01691D02*
X03718Y0169D01*
X03713Y01686*
X03709Y01681*
X03708Y01675*
X03709Y01668*
X03713Y01663*
X03718Y01659*
X03724Y01658*
X03731Y01659*
X03736Y01663*
X03739Y01668*
X03741Y01675*
X03739Y01681*
X03736Y01686*
X03731Y0169*
X03724Y01691*
G37*
G36*
X06602Y01688D02*
X06596Y01687D01*
X06591Y01683*
X06587Y01678*
X06586Y01672*
X06587Y01665*
X06591Y0166*
X06596Y01656*
X06602Y01655*
X06609Y01656*
X06614Y0166*
X06617Y01665*
X06619Y01672*
X06617Y01678*
X06614Y01683*
X06609Y01687*
X06602Y01688*
G37*
G36*
X03968Y01687D02*
X03962Y01686D01*
X03957Y01682*
X03953Y01677*
X03952Y01671*
X03953Y01664*
X03957Y01659*
X03962Y01655*
X03968Y01654*
X03975Y01655*
X0398Y01659*
X03983Y01664*
X03985Y01671*
X03983Y01677*
X0398Y01682*
X03975Y01686*
X03968Y01687*
G37*
G36*
X03773Y01682D02*
X03767Y01681D01*
X03762Y01677*
X03758Y01672*
X03757Y01666*
X03758Y01659*
X03762Y01654*
X03767Y01651*
X03773Y01649*
X0378Y01651*
X03785Y01654*
X03788Y01659*
X0379Y01666*
X03788Y01672*
X03785Y01677*
X0378Y01681*
X03773Y01682*
G37*
G36*
X0359Y01678D02*
X03584Y01677D01*
X03579Y01673*
X03575Y01668*
X03574Y01662*
X03575Y01655*
X03579Y0165*
X03584Y01646*
X0359Y01645*
X03597Y01646*
X03602Y0165*
X03605Y01655*
X03607Y01662*
X03605Y01668*
X03602Y01673*
X03597Y01677*
X0359Y01678*
G37*
G36*
X03224Y01677D02*
X03218Y01676D01*
X03213Y01672*
X03209Y01667*
X03208Y01661*
X03209Y01655*
X03213Y01649*
X03218Y01646*
X03224Y01645*
X03231Y01646*
X03235Y01649*
X03239Y01649*
X03241Y01649*
X03246Y01645*
X03252Y01644*
X03259Y01645*
X03264Y01649*
X03267Y01654*
X03269Y01661*
X03267Y01667*
X03264Y01672*
X03259Y01676*
X03252Y01677*
X03246Y01676*
X03242Y01673*
X03238Y01672*
X03235Y01673*
X03231Y01676*
X03224Y01677*
G37*
G36*
X05578Y01735D02*
X05566Y01734D01*
X05555Y01729*
X05545Y01722*
X05538Y01712*
X05533Y01701*
X05532Y01689*
X05533Y01677*
X05538Y01666*
X05545Y01657*
X05555Y0165*
X05566Y01645*
X05578Y01643*
X0559Y01645*
X05601Y0165*
X0561Y01657*
X05617Y01666*
X05622Y01677*
X05624Y01689*
X05622Y01701*
X05617Y01712*
X0561Y01722*
X05601Y01729*
X0559Y01734*
X05578Y01735*
G37*
G36*
X06602Y01628D02*
X06596Y01627D01*
X06591Y01623*
X06587Y01618*
X06586Y01612*
X06587Y01605*
X06591Y016*
X06596Y01596*
X06602Y01595*
X06609Y01596*
X06614Y016*
X06617Y01605*
X06619Y01612*
X06617Y01618*
X06614Y01623*
X06609Y01627*
X06602Y01628*
G37*
G36*
X04131Y01702D02*
X04125Y01701D01*
X0412Y01697*
X04116Y01692*
X04115Y01686*
X04116Y01679*
X0412Y01674*
X04125Y0167*
X04127Y0167*
X04127Y01669*
X04127Y01665*
X04123Y01662*
X04119Y01657*
X04118Y01651*
X04119Y01644*
X04123Y01639*
X04128Y01635*
X04133Y01634*
X04135Y01631*
X04136Y01629*
X04136Y01629*
X04134Y01623*
X04136Y01617*
X04139Y01612*
X04145Y01608*
X04151Y01607*
X04157Y01608*
X04161Y01611*
X04164Y01607*
X04164Y01607*
X04163Y01601*
X04164Y01594*
X04168Y01589*
X04173Y01585*
X04179Y01584*
X04186Y01585*
X04191Y01589*
X04194Y01594*
X04196Y01601*
X04194Y01607*
X04191Y01612*
X04186Y01616*
X04179Y01617*
X04173Y01616*
X04169Y01613*
X04166Y01617*
X04166Y01617*
X04167Y01623*
X04166Y01629*
X04162Y01635*
X04157Y01638*
X04152Y01639*
X0415Y01643*
X04149Y01644*
X04149Y01644*
X04151Y01651*
X04149Y01657*
X04146Y01662*
X04141Y01666*
X04139Y01666*
X04139Y01667*
X04139Y01671*
X04143Y01674*
X04146Y01679*
X04148Y01686*
X04146Y01692*
X04143Y01697*
X04138Y01701*
X04131Y01702*
G37*
G36*
X03413Y01589D02*
X03407Y01588D01*
X03402Y01584*
X03398Y01579*
X03397Y01573*
X03398Y01566*
X03402Y01561*
X03407Y01557*
X03413Y01556*
X0342Y01557*
X03425Y01561*
X03428Y01566*
X0343Y01573*
X03428Y01579*
X03425Y01584*
X0342Y01588*
X03413Y01589*
G37*
G36*
X03894Y01582D02*
X03888Y01581D01*
X03883Y01577*
X03879Y01572*
X03878Y01566*
X03879Y01559*
X03883Y01554*
X03888Y0155*
X03894Y01549*
X03901Y0155*
X03906Y01554*
X03909Y01559*
X03911Y01566*
X03909Y01572*
X03906Y01577*
X03901Y01581*
X03894Y01582*
G37*
G36*
X03969Y01568D02*
X03963Y01567D01*
X03958Y01563*
X03954Y01558*
X03953Y01552*
X03954Y01545*
X03958Y0154*
X03963Y01536*
X03969Y01535*
X03976Y01536*
X03978Y01538*
X03983Y01539*
X03985Y01537*
X03988Y01535*
X03994Y01534*
X04001Y01535*
X04006Y01539*
X04009Y01544*
X04011Y01551*
X04009Y01557*
X04006Y01562*
X04001Y01566*
X03994Y01567*
X03988Y01566*
X03983Y01562*
X03982*
X03981Y01563*
X03976Y01567*
X03969Y01568*
G37*
G36*
X04034Y01562D02*
X04028Y01561D01*
X04023Y01557*
X04019Y01552*
X04018Y01546*
X04019Y01539*
X04023Y01534*
X04028Y0153*
X04034Y01529*
X04041Y0153*
X04046Y01534*
X04049Y01539*
X04051Y01546*
X04049Y01552*
X04046Y01557*
X04041Y01561*
X04034Y01562*
G37*
G36*
X03924Y01552D02*
X03918Y01551D01*
X03913Y01547*
X03909Y01542*
X03908Y01536*
X03909Y01529*
X03913Y01524*
X03918Y0152*
X03924Y01519*
X03931Y0152*
X03936Y01524*
X03939Y01529*
X03941Y01536*
X03939Y01542*
X03936Y01547*
X03931Y01551*
X03924Y01552*
G37*
G36*
X02894Y01577D02*
X02888Y01576D01*
X02883Y01572*
X02879Y01567*
X02878Y01561*
X02879Y01554*
X02883Y01549*
X02888Y01545*
X02894Y01544*
X02901Y01545*
X02901Y01546*
X02904Y01542*
X02904Y01542*
X02903Y01536*
X02904Y01529*
X02908Y01524*
X02913Y0152*
X02919Y01519*
X02926Y0152*
X02931Y01524*
X02934Y01529*
X02936Y01536*
X02934Y01542*
X02931Y01547*
X02926Y01551*
X02919Y01552*
X02913Y01551*
X02913Y0155*
X02909Y01554*
X02909Y01554*
X02911Y01561*
X02909Y01567*
X02906Y01572*
X02901Y01576*
X02894Y01577*
G37*
G36*
X06548Y01547D02*
X06542Y01546D01*
X06537Y01542*
X06533Y01537*
X06532Y01531*
X06533Y01524*
X06537Y01519*
X06542Y01515*
X06548Y01514*
X06555Y01515*
X0656Y01519*
X06563Y01524*
X06565Y01531*
X06563Y01537*
X0656Y01542*
X06555Y01546*
X06548Y01547*
G37*
G36*
X03594Y0153D02*
X03588Y01529D01*
X03583Y01525*
X03579Y0152*
X03578Y01514*
X03579Y01507*
X03583Y01502*
X03588Y01498*
X03594Y01497*
X03601Y01498*
X03606Y01502*
X03609Y01507*
X03611Y01514*
X03609Y0152*
X03606Y01525*
X03601Y01529*
X03594Y0153*
G37*
G36*
X04064Y01527D02*
X04058Y01526D01*
X04053Y01522*
X04049Y01517*
X04048Y01511*
X04049Y01504*
X04053Y01499*
X04058Y01495*
X04064Y01494*
X04071Y01495*
X04076Y01499*
X04079Y01504*
X04081Y01511*
X04079Y01517*
X04076Y01522*
X04071Y01526*
X04064Y01527*
G37*
G36*
X03864D02*
X03858Y01526D01*
X03853Y01522*
X03849Y01517*
X03848Y01511*
X03849Y01504*
X03853Y01499*
X03858Y01495*
X03864Y01494*
X03871Y01495*
X03876Y01499*
X03879Y01504*
X03881Y01511*
X03879Y01517*
X03876Y01522*
X03871Y01526*
X03864Y01527*
G37*
G36*
X03834Y01497D02*
X03828Y01496D01*
X03823Y01492*
X03819Y01487*
X03818Y01481*
X03819Y01474*
X03823Y01469*
X03828Y01465*
X03834Y01464*
X03841Y01465*
X03846Y01469*
X03849Y01474*
X03851Y01481*
X03849Y01487*
X03846Y01492*
X03841Y01496*
X03834Y01497*
G37*
G36*
X03406Y01477D02*
X034Y01476D01*
X03395Y01472*
X03391Y01467*
X0339Y01461*
X03391Y01454*
X03395Y01449*
X034Y01445*
X03406Y01444*
X03413Y01445*
X03418Y01449*
X03421Y01454*
X03423Y01461*
X03421Y01467*
X03418Y01472*
X03413Y01476*
X03406Y01477*
G37*
G36*
X03732Y01434D02*
X03726Y01433D01*
X03721Y01429*
X03717Y01424*
X03716Y01418*
X03717Y01411*
X03721Y01406*
X03726Y01402*
X03732Y01401*
X03739Y01402*
X03744Y01406*
X03747Y01411*
X03749Y01418*
X03747Y01424*
X03744Y01429*
X03739Y01433*
X03732Y01434*
G37*
G36*
X03407Y01427D02*
X03401Y01426D01*
X03395Y01422*
X03392Y01417*
X0339Y01411*
X03392Y01405*
X03395Y014*
X03391Y01397*
X03386Y01401*
X03379Y01402*
X03373Y01401*
X03368Y01397*
X03364Y01392*
X03363Y01386*
X03364Y01379*
X03368Y01374*
X03373Y0137*
X03379Y01369*
X03385Y0137*
X03388Y01368*
X03389Y01367*
X03388Y01363*
X03389Y01357*
X03392Y01353*
X03392Y01352*
X03389Y01349*
X03388Y01349*
X03386Y01351*
X03379Y01352*
X03373Y01351*
X03368Y01347*
X03364Y01342*
X03363Y01336*
X03364Y01329*
X03368Y01324*
X03373Y0132*
X03379Y01319*
X03386Y0132*
X03391Y01324*
X03394Y01329*
X03396Y01336*
X03394Y01342*
X03392Y01345*
X03392Y01346*
X03395Y0135*
X03396Y01349*
X03398Y01348*
X03404Y01347*
X03411Y01348*
X03416Y01351*
X03419Y01357*
X03421Y01363*
X03419Y01369*
X03416Y01374*
X03411Y01378*
X03404Y01379*
X03399Y01378*
X03396Y0138*
X03395Y01382*
X03396Y01386*
X03394Y01392*
X03391Y01396*
X03395Y01399*
X03401Y01396*
X03407Y01395*
X03413Y01396*
X03418Y01399*
X03422Y01405*
X03423Y01411*
X03422Y01417*
X03418Y01422*
X03413Y01426*
X03407Y01427*
G37*
G36*
X03549Y01457D02*
X03543Y01456D01*
X03538Y01452*
X03534Y01447*
X03533Y01441*
X03534Y01434*
X03538Y01429*
Y01424*
X03534Y01419*
X03533Y01413*
X03534Y01406*
X03538Y01401*
X03543Y01397*
X03549Y01396*
X03556Y01397*
X03561Y01401*
X03564Y01406*
X03566Y01413*
X03564Y01419*
X03561Y01424*
Y01429*
X03564Y01434*
X03566Y01441*
X03564Y01447*
X03561Y01452*
X03556Y01456*
X03549Y01457*
G37*
G36*
X03571Y01328D02*
X03564Y01327D01*
X03558Y01323*
X03554Y01317*
X03552Y01309*
X03554Y01302*
X03558Y01296*
X03564Y01292*
X03571Y0129*
X03579Y01292*
X03585Y01296*
X03589Y01302*
X0359Y01309*
X03589Y01317*
X03585Y01323*
X03579Y01327*
X03571Y01328*
G37*
G36*
X04366Y01045D02*
X04289D01*
Y00968*
X04366*
Y01045*
G37*
G36*
X05327Y01046D02*
X05317Y01045D01*
X05308Y01041*
X053Y01034*
X05294Y01026*
X0529Y01017*
X05288Y01007*
X0529Y00997*
X05294Y00988*
X053Y0098*
X05308Y00973*
X05317Y00969*
X05327Y00968*
X05337Y00969*
X05347Y00973*
X05355Y0098*
X05361Y00988*
X05365Y00997*
X05366Y01007*
X05365Y01017*
X05361Y01026*
X05355Y01034*
X05347Y01041*
X05337Y01045*
X05327Y01046*
G37*
G36*
X05127D02*
X05117Y01045D01*
X05108Y01041*
X051Y01034*
X05094Y01026*
X0509Y01017*
X05088Y01007*
X0509Y00997*
X05094Y00988*
X051Y0098*
X05108Y00973*
X05117Y00969*
X05127Y00968*
X05137Y00969*
X05147Y00973*
X05155Y0098*
X05161Y00988*
X05165Y00997*
X05166Y01007*
X05165Y01017*
X05161Y01026*
X05155Y01034*
X05147Y01041*
X05137Y01045*
X05127Y01046*
G37*
G36*
X04927D02*
X04917Y01045D01*
X04908Y01041*
X049Y01034*
X04894Y01026*
X0489Y01017*
X04888Y01007*
X0489Y00997*
X04894Y00988*
X049Y0098*
X04908Y00973*
X04917Y00969*
X04927Y00968*
X04937Y00969*
X04947Y00973*
X04955Y0098*
X04961Y00988*
X04965Y00997*
X04966Y01007*
X04965Y01017*
X04961Y01026*
X04955Y01034*
X04947Y01041*
X04937Y01045*
X04927Y01046*
G37*
G36*
X03617Y00983D02*
X03604Y00982D01*
X03592Y00978*
X0358Y00972*
X0357Y00963*
X03561Y00953*
X03555Y00942*
X03551Y00929*
X0355Y00916*
X03551Y00903*
X03555Y0089*
X03561Y00878*
X0357Y00868*
X0358Y0086*
X03592Y00854*
X03604Y0085*
X03617Y00848*
X03631Y0085*
X03643Y00854*
X03655Y0086*
X03665Y00868*
X03673Y00878*
X0368Y0089*
X03684Y00903*
X03685Y00916*
X03684Y00929*
X0368Y00942*
X03673Y00953*
X03665Y00963*
X03655Y00972*
X03643Y00978*
X03631Y00982*
X03617Y00983*
G37*
G36*
X05578Y00936D02*
X05566Y00934D01*
X05555Y0093*
X05545Y00923*
X05538Y00913*
X05533Y00902*
X05532Y0089*
X05533Y00878*
X05538Y00867*
X05545Y00858*
X05555Y0085*
X05566Y00846*
X05578Y00844*
X0559Y00846*
X05601Y0085*
X0561Y00858*
X05617Y00867*
X05622Y00878*
X05624Y0089*
X05622Y00902*
X05617Y00913*
X0561Y00923*
X05601Y0093*
X0559Y00934*
X05578Y00936*
G37*
G36*
X03395Y04238D02*
X03389Y04237D01*
X03384Y04233*
X0338Y04228*
X03379Y04222*
X0338Y04215*
X03384Y0421*
X03389Y04206*
X03395Y04205*
X03402Y04206*
X03407Y0421*
X0341Y04215*
X03412Y04222*
X0341Y04228*
X03407Y04233*
X03402Y04237*
X03395Y04238*
G37*
G36*
X02888Y04237D02*
X02882Y04236D01*
X02877Y04232*
X02873Y04227*
X02872Y04221*
X02873Y04214*
X02877Y04209*
X02882Y04205*
X02888Y04204*
X02895Y04205*
X029Y04209*
X02903Y04214*
X02905Y04221*
X02903Y04227*
X029Y04232*
X02895Y04236*
X02888Y04237*
G37*
G36*
X0229Y04233D02*
X02284Y04232D01*
X02279Y04228*
X02275Y04223*
X02274Y04217*
X02275Y0421*
X02279Y04205*
X02284Y04201*
X0229Y042*
X02297Y04201*
X02302Y04205*
X02305Y0421*
X02307Y04217*
X02305Y04223*
X02302Y04228*
X02297Y04232*
X0229Y04233*
G37*
G36*
X04387Y04222D02*
X04381Y04221D01*
X04376Y04217*
X04372Y04212*
X04371Y04206*
X04372Y04199*
X04376Y04194*
X04381Y0419*
X04387Y04189*
X04394Y0419*
X04399Y04194*
X04402Y04199*
X04404Y04206*
X04402Y04212*
X04399Y04217*
X04394Y04221*
X04387Y04222*
G37*
G36*
X0491Y04219D02*
X04904Y04218D01*
X04899Y04214*
X04895Y04209*
X04894Y04203*
X04895Y04196*
X04899Y04191*
X04904Y04187*
X0491Y04186*
X04917Y04187*
X04922Y04191*
X04925Y04196*
X04927Y04203*
X04925Y04209*
X04922Y04214*
X04917Y04218*
X0491Y04219*
G37*
G36*
X03958Y04152D02*
X03951Y04151D01*
X03945Y04148*
X03939Y04144*
X03935Y04139*
X03933Y04132*
X03932Y04126*
X03933Y04119*
X03935Y04113*
X03939Y04107*
X03945Y04103*
X03951Y04101*
X03958Y041*
X03964Y04101*
X03971Y04103*
X03976Y04107*
X0398Y04113*
X03983Y04119*
X03984Y04126*
X03983Y04132*
X0398Y04139*
X03976Y04144*
X03971Y04148*
X03964Y04151*
X03958Y04152*
G37*
G36*
X03784D02*
X03778Y04151D01*
X03771Y04148*
X03766Y04144*
X03762Y04139*
X03759Y04132*
X03758Y04126*
X03759Y04119*
X03762Y04113*
X03766Y04107*
X03771Y04103*
X03778Y04101*
X03784Y041*
X03791Y04101*
X03797Y04103*
X03803Y04107*
X03807Y04113*
X03809Y04119*
X0381Y04126*
X03809Y04132*
X03807Y04139*
X03803Y04144*
X03797Y04148*
X03791Y04151*
X03784Y04152*
G37*
G36*
X04754Y04132D02*
X04748Y04131D01*
X04743Y04127*
X04739Y04122*
X04738Y04115*
X04739Y04109*
X04743Y04104*
X04748Y041*
X04754Y04099*
X0476Y041*
X04766Y04104*
X04769Y04109*
X04771Y04115*
X04769Y04122*
X04766Y04127*
X0476Y04131*
X04754Y04132*
G37*
G36*
X02146Y0412D02*
X02139Y04118D01*
X02134Y04115*
X02131Y0411*
X02129Y04103*
X02131Y04097*
X02134Y04092*
X02139Y04088*
X02146Y04087*
X02152Y04088*
X02157Y04092*
X02161Y04097*
X02162Y04103*
X02161Y0411*
X02157Y04115*
X02152Y04118*
X02146Y0412*
G37*
G36*
X05267Y04105D02*
X0526Y04103D01*
X05255Y041*
X05251Y04095*
X0525Y04088*
X05251Y04082*
X05255Y04077*
X0526Y04073*
X05267Y04072*
X05273Y04073*
X05278Y04077*
X05282Y04082*
X05283Y04088*
X05282Y04095*
X05278Y041*
X05273Y04103*
X05267Y04105*
G37*
G36*
X02253Y04102D02*
X02247Y04101D01*
X02242Y04098*
X02238Y04092*
X02237Y04086*
X02238Y0408*
X02242Y04075*
X02247Y04071*
X02253Y0407*
X0226Y04071*
X02265Y04075*
X02269Y0408*
X0227Y04086*
X02269Y04092*
X02265Y04098*
X0226Y04101*
X02253Y04102*
G37*
G36*
X03504Y04102D02*
X03498Y04101D01*
X03493Y04097*
X03489Y04092*
X03488Y04086*
X03489Y04079*
X03493Y04074*
X03498Y0407*
X03504Y04069*
X03511Y0407*
X03516Y04074*
X03519Y04079*
X03521Y04086*
X03519Y04092*
X03516Y04097*
X03511Y04101*
X03504Y04102*
G37*
G36*
X03294Y04127D02*
X03284Y04126D01*
X03274Y04121*
X03265Y04115*
X03259Y04106*
X03254Y04096*
X03253Y04086*
X03254Y04075*
X03259Y04065*
X03265Y04056*
X03274Y0405*
X03284Y04046*
X03294Y04044*
X03305Y04046*
X03315Y0405*
X03324Y04056*
X0333Y04065*
X03334Y04075*
X03336Y04086*
X03334Y04096*
X0333Y04106*
X03324Y04115*
X03315Y04121*
X03305Y04126*
X03294Y04127*
G37*
G36*
X02994D02*
X02984Y04126D01*
X02974Y04121*
X02965Y04115*
X02959Y04106*
X02954Y04096*
X02953Y04086*
X02954Y04075*
X02959Y04065*
X02965Y04056*
X02974Y0405*
X02984Y04046*
X02994Y04044*
X03005Y04046*
X03015Y0405*
X03024Y04056*
X0303Y04065*
X03034Y04075*
X03036Y04086*
X03034Y04096*
X0303Y04106*
X03024Y04115*
X03015Y04121*
X03005Y04126*
X02994Y04127*
G37*
G36*
X03777Y04039D02*
X03771Y04038D01*
X03766Y04034*
X03762Y04029*
X03761Y04023*
X03762Y04016*
X03766Y04011*
X03771Y04007*
X03777Y04006*
X03784Y04007*
X03789Y04011*
X03792Y04016*
X03794Y04023*
X03792Y04029*
X03789Y04034*
X03784Y04038*
X03777Y04039*
G37*
G36*
X06164Y04108D02*
X06075D01*
X06061Y04107*
X06049Y04101*
X06038Y04093*
X06029Y04082*
X06024Y04069*
X06022Y04056*
X06024Y04042*
X06029Y04029*
X06038Y04018*
X06049Y0401*
X06061Y04005*
X06075Y04003*
X06164*
X06177Y04005*
X0619Y0401*
X06201Y04018*
X06209Y04029*
X06215Y04042*
X06216Y04056*
X06215Y04069*
X06209Y04082*
X06201Y04093*
X0619Y04101*
X06177Y04107*
X06164Y04108*
G37*
G36*
X02353Y04034D02*
X02347Y04032D01*
X02341Y04029*
X02338Y04023*
X02337Y04017*
X02338Y04011*
X02341Y04006*
X02347Y04002*
X02353Y04001*
X02359Y04002*
X02364Y04006*
X02368Y04011*
X02369Y04017*
X02368Y04023*
X02364Y04029*
X02359Y04032*
X02353Y04034*
G37*
G36*
X05723Y04083D02*
X05708Y04081D01*
X05694Y04075*
X05682Y04066*
X05673Y04054*
X05667Y0404*
X05665Y04025*
X05667Y0401*
X05673Y03996*
X05682Y03984*
X05694Y03975*
X05708Y03969*
X05723Y03967*
X05738Y03969*
X05752Y03975*
X05764Y03984*
X05773Y03996*
X05779Y0401*
X05781Y04025*
X05779Y0404*
X05773Y04054*
X05764Y04066*
X05752Y04075*
X05738Y04081*
X05723Y04083*
G37*
G36*
X02084Y03912D02*
X02078Y03911D01*
X02073Y03907*
X02069Y03902*
X02068Y03896*
X02069Y03889*
X02069Y03889*
X02066Y03885*
X02066Y03886*
X02059Y03887*
X02053Y03886*
X02048Y03882*
X02044Y03877*
X02043Y03871*
X02044Y03864*
X02048Y03859*
X02053Y03855*
X02059Y03854*
X02066Y03855*
X02071Y03859*
X02074Y03864*
X02076Y03871*
X02074Y03877*
X02074Y03877*
X02078Y03881*
X02078Y0388*
X02084Y03879*
X02091Y0388*
X02096Y03884*
X02099Y03889*
X02101Y03896*
X02099Y03902*
X02096Y03907*
X02091Y03911*
X02084Y03912*
G37*
G36*
X05934Y04034D02*
X05921Y04033D01*
X05908Y04027*
X05897Y04019*
X05889Y04008*
X05883Y03995*
X05882Y03982*
Y03893*
X05883Y0388*
X05889Y03867*
X05897Y03856*
X05908Y03847*
X05921Y03842*
X05934Y0384*
X05948Y03842*
X05961Y03847*
X05972Y03856*
X0598Y03867*
X05985Y0388*
X05987Y03893*
Y03982*
X05985Y03995*
X0598Y04008*
X05972Y04019*
X05961Y04027*
X05948Y04033*
X05934Y04034*
G37*
G36*
X03699Y03852D02*
X03693Y03851D01*
X03688Y03847*
X03684Y03842*
X03683Y03836*
X03684Y03829*
X03688Y03824*
X03693Y0382*
X03699Y03819*
X03706Y0382*
X03711Y03824*
X03714Y03829*
X03716Y03836*
X03714Y03842*
X03711Y03847*
X03706Y03851*
X03699Y03852*
G37*
G36*
X03014Y03847D02*
X03008Y03846D01*
X03003Y03842*
X02999Y03837*
X02998Y03831*
X02999Y03824*
X03003Y03819*
X03008Y03815*
X03014Y03814*
X03021Y03815*
X03026Y03819*
X03029Y03824*
X03031Y03831*
X03029Y03837*
X03026Y03842*
X03021Y03846*
X03014Y03847*
G37*
G36*
X05723Y03902D02*
X05708Y039D01*
X05694Y03894*
X05682Y03885*
X05673Y03873*
X05667Y03859*
X05665Y03844*
X05667Y03829*
X05673Y03815*
X05682Y03803*
X05694Y03794*
X05708Y03788*
X05723Y03786*
X05738Y03788*
X05752Y03794*
X05764Y03803*
X05773Y03815*
X05779Y03829*
X05781Y03844*
X05779Y03859*
X05773Y03873*
X05764Y03885*
X05752Y03894*
X05738Y039*
X05723Y03902*
G37*
G36*
X03269Y03804D02*
X03263Y03803D01*
X03258Y03799*
X03254Y03794*
X03253Y03788*
X03254Y03781*
X03258Y03776*
X03263Y03772*
X03269Y03771*
X03276Y03772*
X03281Y03776*
X03284Y03781*
X03286Y03788*
X03284Y03794*
X03281Y03799*
X03276Y03803*
X03269Y03804*
G37*
G36*
X0286Y03803D02*
X02854Y03802D01*
X02849Y03798*
X02845Y03793*
X02844Y03787*
X02845Y0378*
X02849Y03775*
X02854Y03771*
X0286Y0377*
X02867Y03771*
X02872Y03775*
X02875Y0378*
X02877Y03787*
X02875Y03793*
X02872Y03798*
X02867Y03802*
X0286Y03803*
G37*
G36*
X06169Y03877D02*
X0607D01*
X06055Y03875*
X06041Y03869*
X06029Y0386*
X0602Y03848*
X06014Y03834*
X06012Y03819*
X06014Y03804*
X0602Y0379*
X06029Y03779*
X06041Y03769*
X06055Y03764*
X0607Y03762*
X06169*
X06183Y03764*
X06197Y03769*
X06209Y03779*
X06219Y0379*
X06224Y03804*
X06226Y03819*
X06224Y03834*
X06219Y03848*
X06209Y0386*
X06197Y03869*
X06183Y03875*
X06169Y03877*
G37*
G36*
X0383Y03778D02*
X03824Y03777D01*
X03819Y03773*
X03815Y03768*
X03814Y03762*
X03815Y03755*
X03819Y0375*
X03824Y03746*
X0383Y03745*
X03837Y03746*
X03842Y0375*
X03845Y03755*
X03847Y03762*
X03845Y03768*
X03842Y03773*
X03837Y03777*
X0383Y03778*
G37*
G36*
X02531Y03962D02*
X02514Y0396D01*
X02497Y03956*
X02482Y0395*
X02467Y03941*
X02454Y0393*
X02443Y03917*
X02434Y03902*
X02428Y03887*
X02424Y0387*
X02423Y03853*
X02424Y03836*
X02428Y0382*
X02434Y03804*
X02443Y03789*
X02454Y03777*
X02467Y03766*
X02482Y03757*
X02497Y0375*
X02514Y03746*
X02531Y03745*
X02548Y03746*
X02564Y0375*
X0258Y03757*
X02595Y03766*
X02608Y03777*
X02619Y03789*
X02627Y03804*
X02634Y0382*
X02638Y03836*
X02639Y03853*
X02638Y0387*
X02634Y03887*
X02627Y03902*
X02619Y03917*
X02608Y0393*
X02595Y03941*
X0258Y0395*
X02564Y03956*
X02548Y0396*
X02531Y03962*
G37*
G36*
X03699Y03767D02*
X03693Y03766D01*
X03688Y03762*
X03684Y03757*
X03683Y03751*
X03684Y03744*
X03688Y03739*
X03693Y03735*
X03699Y03734*
X03706Y03735*
X03711Y03739*
X03714Y03744*
X03716Y03751*
X03714Y03757*
X03711Y03762*
X03706Y03766*
X03699Y03767*
G37*
G36*
X02993D02*
X02987Y03766D01*
X02981Y03762*
X02978Y03757*
X02977Y03751*
X02978Y03744*
X02981Y03739*
X02987Y03735*
X02993Y03734*
X02999Y03735*
X03004Y03739*
X03008Y03744*
X03009Y03751*
X03008Y03757*
X03004Y03762*
X02999Y03766*
X02993Y03767*
G37*
G36*
X02258Y03757D02*
X02252Y03756D01*
X02247Y03752*
X02243Y03747*
X02242Y03741*
X02243Y03734*
X02247Y03729*
X02252Y03725*
X02258Y03724*
X02265Y03725*
X0227Y03729*
X02273Y03734*
X02275Y03741*
X02273Y03747*
X0227Y03752*
X02265Y03756*
X02258Y03757*
G37*
G36*
X02139Y03754D02*
X02133Y03753D01*
X02128Y03749*
X02124Y03744*
X02123Y03738*
X02124Y03731*
X02128Y03726*
X02133Y03722*
X02139Y03721*
X02146Y03722*
X02151Y03726*
X02154Y03731*
X02156Y03738*
X02154Y03744*
X02151Y03749*
X02146Y03753*
X02139Y03754*
G37*
G36*
X02724Y03745D02*
X02718Y03744D01*
X02713Y0374*
X02709Y03735*
X02708Y03729*
X02709Y03722*
X02713Y03717*
X02718Y03713*
X02724Y03712*
X02731Y03713*
X02736Y03717*
X02739Y03722*
X02741Y03729*
X02739Y03735*
X02736Y0374*
X02731Y03744*
X02724Y03745*
G37*
G36*
X02422Y03624D02*
X02413Y03623D01*
X02405Y03617*
X024Y0361*
X02398Y03601*
X024Y03592*
X02405Y03584*
X02413Y03579*
X02422Y03577*
X02431Y03579*
X02438Y03584*
X02443Y03592*
X02445Y03601*
X02443Y0361*
X02438Y03617*
X02431Y03623*
X02422Y03624*
G37*
G36*
X05733Y03572D02*
X05727Y03571D01*
X05722Y03567*
X05718Y03562*
X05717Y03556*
X05718Y03549*
X05722Y03544*
X05727Y0354*
X05733Y03539*
X0574Y0354*
X05745Y03544*
X05748Y03549*
X0575Y03556*
X05748Y03562*
X05745Y03567*
X0574Y03571*
X05733Y03572*
G37*
G36*
X05676Y03562D02*
X0567Y03561D01*
X05665Y03557*
X05661Y03552*
X0566Y03546*
X05661Y03539*
X05665Y03534*
X0567Y0353*
X05676Y03529*
X05683Y0353*
X05688Y03534*
X05691Y03539*
X05693Y03546*
X05691Y03552*
X05688Y03557*
X05683Y03561*
X05676Y03562*
G37*
G36*
X02434D02*
X02428Y03561D01*
X02423Y03557*
X02419Y03552*
X02418Y03546*
X02419Y03539*
X02423Y03534*
X02428Y0353*
X02434Y03529*
X02441Y0353*
X02446Y03534*
X02449Y03539*
X02451Y03546*
X02449Y03552*
X02446Y03557*
X02441Y03561*
X02434Y03562*
G37*
G36*
X02254Y03552D02*
X02248Y03551D01*
X02243Y03547*
X02239Y03542*
X02238Y03536*
X02239Y03529*
X02242Y03525*
X02239Y03521*
X02234Y03522*
X02228Y03521*
X02223Y03517*
X02219Y03512*
X02218Y03506*
X02219Y03499*
X02223Y03494*
X02228Y0349*
X02234Y03489*
X02241Y0349*
X02246Y03494*
X02249Y03499*
X02251Y03506*
X02249Y03512*
X02247Y03516*
X0225Y0352*
X02254Y03519*
X02261Y0352*
X02266Y03524*
X02269Y03529*
X02271Y03536*
X02269Y03542*
X02266Y03547*
X02261Y03551*
X02254Y03552*
G37*
G36*
X02389Y03497D02*
X02383Y03496D01*
X02378Y03492*
X02374Y03487*
X02373Y03481*
X02374Y03474*
X02378Y03469*
X02383Y03465*
X02389Y03464*
X02396Y03465*
X02401Y03469*
X02404Y03474*
X02406Y03481*
X02404Y03487*
X02401Y03492*
X02396Y03496*
X02389Y03497*
G37*
G36*
X02422Y03467D02*
X02413Y03465D01*
X02405Y0346*
X024Y03452*
X02398Y03443*
X024Y03434*
X02405Y03427*
X02413Y03422*
X02422Y0342*
X02431Y03422*
X02438Y03427*
X02443Y03434*
X02445Y03443*
X02443Y03452*
X02438Y0346*
X02431Y03465*
X02422Y03467*
G37*
G36*
X02321Y03377D02*
X02315Y03376D01*
X0231Y03372*
X02306Y03367*
X02305Y03361*
X02306Y03354*
X0231Y03349*
X02315Y03345*
X02321Y03344*
X02327Y03345*
X02333Y03349*
X02336Y03354*
X02337Y03361*
X02336Y03367*
X02333Y03372*
X02327Y03376*
X02321Y03377*
G37*
G36*
X02259Y03277D02*
X02253Y03276D01*
X02248Y03272*
X02244Y03267*
X02243Y03261*
X02244Y03254*
X02248Y03249*
X02253Y03245*
X02259Y03244*
X02266Y03245*
X02271Y03249*
X02274Y03254*
X02276Y03261*
X02274Y03267*
X02271Y03272*
X02266Y03276*
X02259Y03277*
G37*
G36*
X02205Y03216D02*
X02199Y03215D01*
X02194Y03211*
X0219Y03206*
X02189Y032*
X0219Y03193*
X02194Y03188*
X02199Y03184*
X02205Y03183*
X02212Y03184*
X02217Y03188*
X0222Y03193*
X02222Y032*
X0222Y03206*
X02217Y03211*
X02212Y03215*
X02205Y03216*
G37*
G36*
X04477Y03151D02*
X04471Y0315D01*
X04466Y03146*
X04462Y03141*
X04461Y03135*
X04462Y03128*
X04466Y03123*
X04471Y03119*
X04477Y03118*
X04484Y03119*
X04489Y03123*
X04492Y03128*
X04494Y03135*
X04492Y03141*
X04489Y03146*
X04484Y0315*
X04477Y03151*
G37*
G36*
X04431D02*
X04425Y0315D01*
X0442Y03146*
X04416Y03141*
X04415Y03135*
X04416Y03128*
X0442Y03123*
X04425Y03119*
X04431Y03118*
X04438Y03119*
X04443Y03123*
X04446Y03128*
X04448Y03135*
X04446Y03141*
X04443Y03146*
X04438Y0315*
X04431Y03151*
G37*
G36*
X06253Y02925D02*
X06247Y02924D01*
X06242Y0292*
X06238Y02915*
X06237Y02909*
X06238Y02903*
X06242Y02897*
X06247Y02894*
X06253Y02893*
X0626Y02894*
X06265Y02897*
X06269Y02903*
X0627Y02909*
X06269Y02915*
X06265Y0292*
X0626Y02924*
X06253Y02925*
G37*
G36*
X04794Y02824D02*
X04788Y02823D01*
X04782Y02819*
X04779Y02814*
X04777Y02808*
X04779Y02801*
X04782Y02796*
X04788Y02793*
X04794Y02791*
X048Y02793*
X04805Y02796*
X04809Y02801*
X0481Y02808*
X04809Y02814*
X04805Y02819*
X048Y02823*
X04794Y02824*
G37*
G36*
X05578Y02534D02*
X05566Y02533D01*
X05555Y02528*
X05545Y02521*
X05538Y02511*
X05533Y025*
X05532Y02489*
X05533Y02477*
X05538Y02466*
X05545Y02456*
X05555Y02449*
X05566Y02444*
X05578Y02443*
X0559Y02444*
X05601Y02449*
X0561Y02456*
X05617Y02466*
X05622Y02477*
X05624Y02489*
X05622Y025*
X05617Y02511*
X0561Y02521*
X05601Y02528*
X0559Y02533*
X05578Y02534*
G37*
G36*
X06004Y0245D02*
X05998Y02449D01*
X05993Y02445*
X05989Y0244*
X05988Y02434*
X05989Y02427*
X05993Y02422*
X05998Y02418*
X06004Y02417*
X06011Y02418*
X06016Y02422*
X06019Y02427*
X06021Y02434*
X06019Y0244*
X06016Y02445*
X06011Y02449*
X06004Y0245*
G37*
G36*
X069Y03647D02*
X06885Y03645D01*
X06871Y03639*
X06859Y0363*
X0685Y03618*
X06844Y03604*
X06842Y03589*
X06844Y03574*
X0685Y0356*
X06859Y03548*
X06871Y03539*
X06885Y03533*
X069Y03531*
X06915Y03533*
X06929Y03539*
X06941Y03548*
X0695Y0356*
X06955Y03574*
X06957Y03589*
X06955Y03604*
X0695Y03618*
X06941Y0363*
X06929Y03639*
X06915Y03645*
X069Y03647*
G37*
G36*
X06734D02*
X06719Y03645D01*
X06705Y03639*
X06694Y0363*
X06684Y03618*
X06679Y03604*
X06677Y03589*
X06679Y03574*
X06684Y0356*
X06694Y03548*
X06705Y03539*
X06719Y03533*
X06734Y03531*
X06749Y03533*
X06763Y03539*
X06775Y03548*
X06784Y0356*
X0679Y03574*
X06792Y03589*
X0679Y03604*
X06784Y03618*
X06775Y0363*
X06763Y03639*
X06749Y03645*
X06734Y03647*
G37*
G36*
X06569D02*
X06554Y03645D01*
X0654Y03639*
X06528Y0363*
X06519Y03618*
X06513Y03604*
X06511Y03589*
X06513Y03574*
X06519Y0356*
X06528Y03548*
X0654Y03539*
X06554Y03533*
X06569Y03531*
X06584Y03533*
X06598Y03539*
X0661Y03548*
X06619Y0356*
X06625Y03574*
X06627Y03589*
X06625Y03604*
X06619Y03618*
X0661Y0363*
X06598Y03639*
X06584Y03645*
X06569Y03647*
G37*
G36*
X06509Y03472D02*
X06503Y03471D01*
X06498Y03467*
X06494Y03462*
X06493Y03456*
X06494Y03449*
X06498Y03444*
X06503Y0344*
X06509Y03439*
X06516Y0344*
X06521Y03444*
X06524Y03449*
X06526Y03456*
X06524Y03462*
X06521Y03467*
X06516Y03471*
X06509Y03472*
G37*
G36*
X06479Y03442D02*
X06473Y03441D01*
X06468Y03437*
X06464Y03432*
X06463Y03426*
X06464Y03419*
X06468Y03414*
X06473Y0341*
X06479Y03409*
X06486Y0341*
X06491Y03414*
X06494Y03419*
X06496Y03426*
X06494Y03432*
X06491Y03437*
X06486Y03441*
X06479Y03442*
G37*
G36*
X06447Y03412D02*
X06441Y03411D01*
X06436Y03407*
X06432Y03402*
X06431Y03396*
X06432Y03389*
X06436Y03384*
X06441Y0338*
X06447Y03379*
X06453Y0338*
X06459Y03384*
X06462Y03389*
X06463Y03396*
X06462Y03402*
X06459Y03407*
X06453Y03411*
X06447Y03412*
G37*
G36*
X06409Y03387D02*
X06403Y03386D01*
X06398Y03382*
X06394Y03377*
X06393Y03371*
X06394Y03364*
X06398Y03359*
X06403Y03355*
X06409Y03354*
X06416Y03355*
X06421Y03359*
X06424Y03364*
X06426Y03371*
X06424Y03377*
X06421Y03382*
X06416Y03386*
X06409Y03387*
G37*
G36*
X06648Y03357D02*
X06642Y03356D01*
X06637Y03352*
X06633Y03347*
X06632Y03341*
X06633Y03334*
X06637Y03329*
X06642Y03325*
X06648Y03324*
X06655Y03325*
X0666Y03329*
X06663Y03334*
X06665Y03341*
X06663Y03347*
X0666Y03352*
X06655Y03356*
X06648Y03357*
G37*
G36*
X06354Y03347D02*
X06348Y03346D01*
X06343Y03342*
X06339Y03337*
X06338Y03331*
X06339Y03324*
X06343Y03319*
X06348Y03316*
X06354Y03314*
X0636Y03316*
X06366Y03319*
X06369Y03324*
X06371Y03331*
X06369Y03337*
X06366Y03342*
X0636Y03346*
X06354Y03347*
G37*
G36*
X06444Y03307D02*
X06438Y03306D01*
X06433Y03302*
X06429Y03297*
X06428Y03291*
X06429Y03284*
X06433Y03279*
X06438Y03275*
X06444Y03274*
X06451Y03275*
X06456Y03279*
X06459Y03284*
X06461Y03291*
X06459Y03297*
X06456Y03302*
X06451Y03306*
X06444Y03307*
G37*
G36*
X06334Y03282D02*
X06328Y03281D01*
X06323Y03277*
X06319Y03272*
X06318Y03266*
X06319Y03259*
X06323Y03254*
X06328Y0325*
X06334Y03249*
X06341Y0325*
X06346Y03254*
X06349Y03259*
X06351Y03266*
X06349Y03272*
X06346Y03277*
X06341Y03281*
X06334Y03282*
G37*
G36*
X06476Y03247D02*
X0647Y03246D01*
X06465Y03242*
X06461Y03237*
X0646Y03231*
X06461Y03224*
X06465Y03219*
X0647Y03215*
X06476Y03214*
X06483Y03215*
X06488Y03219*
X06491Y03224*
X06493Y03231*
X06491Y03237*
X06488Y03242*
X06483Y03246*
X06476Y03247*
G37*
G36*
X06282Y03242D02*
X06276Y03241D01*
X0627Y03237*
X06267Y03232*
X06266Y03226*
X06267Y03219*
X0627Y03214*
X06276Y0321*
X06282Y03209*
X06288Y0321*
X06293Y03214*
X06297Y03219*
X06298Y03226*
X06297Y03232*
X06293Y03237*
X06288Y03241*
X06282Y03242*
G37*
G36*
X06309Y03215D02*
X06303Y03214D01*
X06297Y0321*
X06294Y03205*
X06293Y03199*
X06294Y03192*
X06297Y03187*
X06303Y03183*
X06309Y03182*
X06315Y03183*
X0632Y03187*
X06324Y03192*
X06325Y03199*
X06324Y03205*
X0632Y0321*
X06315Y03214*
X06309Y03215*
G37*
G36*
X06439Y03207D02*
X06433Y03206D01*
X06428Y03202*
X06424Y03197*
X06423Y03191*
X06424Y03184*
X06428Y03179*
X06433Y03175*
X06439Y03174*
X06446Y03175*
X06451Y03179*
X06454Y03184*
X06456Y03191*
X06454Y03197*
X06451Y03202*
X06446Y03206*
X06439Y03207*
G37*
G36*
X06339Y03167D02*
X06333Y03166D01*
X06328Y03162*
X06324Y03157*
X06323Y03151*
X06324Y03144*
X06328Y03139*
X06333Y03135*
X06339Y03134*
X06346Y03135*
X06351Y03139*
X06354Y03144*
X06356Y03151*
X06354Y03157*
X06351Y03162*
X06346Y03166*
X06339Y03167*
G37*
G36*
X06647Y03146D02*
X06641Y03144D01*
X06636Y03141*
X06632Y03136*
X06631Y03129*
X06632Y03123*
X06636Y03118*
X06641Y03114*
X06647Y03113*
X06653Y03114*
X06659Y03118*
X06662Y03123*
X06663Y03129*
X06662Y03136*
X06659Y03141*
X06653Y03144*
X06647Y03146*
G37*
G36*
X06304Y03137D02*
X06298Y03136D01*
X06293Y03132*
X06289Y03127*
X06288Y03121*
X06289Y03114*
X06293Y03109*
X06298Y03105*
X06304Y03104*
X06311Y03105*
X06316Y03109*
X06319Y03114*
X06321Y03121*
X06319Y03127*
X06316Y03132*
X06311Y03136*
X06304Y03137*
G37*
G36*
X06626Y03048D02*
X0662Y03047D01*
X06615Y03043*
X06611Y03038*
X0661Y03032*
X06611Y03025*
X06615Y0302*
X0662Y03016*
X06626Y03015*
X06633Y03016*
X06638Y0302*
X06641Y03025*
X06643Y03032*
X06641Y03038*
X06638Y03043*
X06633Y03047*
X06626Y03048*
G37*
G36*
X06456Y03025D02*
X0645Y03024D01*
X06445Y0302*
X06441Y03015*
X0644Y03009*
X06441Y03002*
X06445Y02997*
X0645Y02993*
X06456Y02992*
X06463Y02993*
X06468Y02997*
X06471Y03002*
X06473Y03009*
X06471Y03015*
X06468Y0302*
X06463Y03024*
X06456Y03025*
G37*
G36*
X06372Y02925D02*
X06365Y02924D01*
X0636Y0292*
X06356Y02915*
X06355Y02909*
X06356Y02903*
X0636Y02897*
X06365Y02894*
X06372Y02893*
X06378Y02894*
X06383Y02897*
X06387Y02903*
X06388Y02909*
X06387Y02915*
X06383Y0292*
X06378Y02924*
X06372Y02925*
G37*
G36*
X06398Y02673D02*
X06392Y02672D01*
X06387Y02668*
X06383Y02663*
X06382Y02657*
X06383Y0265*
X06387Y02645*
X06392Y02641*
X06398Y0264*
X06405Y02641*
X0641Y02645*
X06413Y0265*
X06415Y02657*
X06413Y02663*
X0641Y02668*
X06405Y02672*
X06398Y02673*
G37*
G36*
X06397Y02626D02*
X06391Y02625D01*
X06386Y02621*
X06382Y02616*
X06381Y0261*
X06382Y02603*
X06386Y02598*
X06391Y02594*
X06397Y02593*
X06404Y02594*
X06409Y02598*
X06412Y02603*
X06414Y0261*
X06412Y02616*
X06409Y02621*
X06404Y02625*
X06397Y02626*
G37*
G36*
X06396Y02572D02*
X0639Y02571D01*
X06385Y02567*
X06381Y02562*
X0638Y02556*
X06381Y02549*
X06385Y02544*
X0639Y0254*
X06396Y02539*
X06403Y0254*
X06408Y02544*
X06411Y02549*
X06413Y02556*
X06411Y02562*
X06408Y02567*
X06403Y02571*
X06396Y02572*
G37*
G36*
X06397Y02517D02*
X06391Y02516D01*
X06386Y02512*
X06382Y02507*
X06381Y02501*
X06382Y02494*
X06386Y02489*
X06391Y02485*
X06397Y02484*
X06404Y02485*
X06409Y02489*
X06412Y02494*
X06414Y02501*
X06412Y02507*
X06409Y02512*
X06404Y02516*
X06397Y02517*
G37*
G36*
X06398Y02469D02*
X06392Y02468D01*
X06387Y02464*
X06383Y02459*
X06382Y02453*
X06383Y02446*
X06387Y02441*
X06392Y02437*
X06398Y02436*
X06405Y02437*
X0641Y02441*
X06413Y02446*
X06415Y02453*
X06413Y02459*
X0641Y02464*
X06405Y02468*
X06398Y02469*
G37*
G36*
X06607Y02192D02*
X06601Y02191D01*
X06596Y02187*
X06592Y02182*
X06591Y02176*
X06592Y02169*
X06596Y02164*
X06601Y0216*
X06607Y02159*
X06614Y0216*
X06619Y02164*
X06622Y02169*
X06624Y02176*
X06622Y02182*
X06619Y02187*
X06614Y02191*
X06607Y02192*
G37*
G36*
X06949Y02111D02*
X06943Y0211D01*
X06938Y02106*
X06934Y02101*
X06933Y02095*
X06934Y02088*
X06938Y02083*
X06943Y02079*
X06949Y02078*
X06956Y02079*
X06961Y02083*
X06964Y02088*
X06966Y02095*
X06964Y02101*
X06961Y02106*
X06956Y0211*
X06949Y02111*
G37*
G36*
X06974Y01956D02*
X06968Y01955D01*
X06962Y01951*
X06959Y01946*
X06958Y01939*
X06959Y01933*
X06962Y01928*
X06968Y01924*
X06974Y01923*
X0698Y01924*
X06985Y01928*
X06989Y01933*
X0699Y01939*
X06989Y01946*
X06985Y01951*
X0698Y01955*
X06974Y01956*
G37*
%LNgrandmaster-3*%
%LPD*%
G54D13*
X02415Y02792D02*
Y02823D01*
Y02792D02*
X02419Y02788D01*
X02394Y02845D02*
X02415Y02823D01*
X02397Y03279D02*
X02413Y03295D01*
X02631Y02876D02*
X02632Y02877D01*
Y02971*
X02434Y0298D02*
X02473D01*
X02421Y02967D02*
X02434Y0298D01*
X02398Y02949D02*
X02415Y02967D01*
X02421*
X02398Y02944D02*
Y02949D01*
X02334Y03279D02*
X02397D01*
X02385Y02854D02*
X02386D01*
X02394Y02846*
Y02845D02*
Y02846D01*
G54D19*
X01798Y0013D02*
Y00355D01*
X01896Y00735D02*
X02191Y0044D01*
X02349Y00111D02*
X02349Y00111D01*
X02191Y00111D02*
Y0044D01*
X01896Y01516D02*
X01897Y01516D01*
X01896Y00735D02*
Y01516D01*
X03018Y00111D02*
X03019Y00112D01*
X02703Y00111D02*
X02704Y00112D01*
X02711Y03002D02*
Y03003D01*
X02681Y02971D02*
X02711Y03002D01*
X02632Y02971D02*
X02681D01*
X0259Y03187D02*
X02591Y03186D01*
X02529Y03121D02*
X02591Y03184D01*
Y03186*
X02589Y03287D02*
X0259Y03288D01*
X02583Y03279D02*
X02589Y03285D01*
X02509Y03279D02*
X02583D01*
X02589Y03285D02*
Y03287D01*
X02415Y03121D02*
X02418Y03118D01*
X02334Y03121D02*
X02415D01*
X02334Y032D02*
X02335Y03199D01*
X02414*
X02462Y03172D02*
X0249Y032D01*
X02509*
Y03121D02*
X02529D01*
X04049Y03665D02*
Y03701D01*
X03944Y03806D02*
X04049Y03701D01*
X03829Y03806D02*
X03944D01*
G54D21*
X0298Y00408D02*
D01*
X0298Y00408*
X0298Y00408*
X0298Y00407*
X02821Y00407D02*
D01*
X02821Y00407*
X02821Y00407*
X02821Y00407*
X0282Y00407*
X0282Y00406*
X0282Y00406*
X0282Y00406*
X02819Y00406*
X02819Y00405*
X02819Y00405*
X02819Y00405*
X02819Y00404*
X02819Y00404*
X02818Y00404*
X02818Y00403*
X02818Y00403*
Y00403*
X02469Y0041D02*
D01*
X02469Y0041*
X02469Y0041*
X02469Y0041*
X02469Y00409*
X02468Y00409*
X02468Y00409*
X02468Y00408*
X02468Y00408*
X02468Y00408*
X02468Y00407*
X02468Y00407*
X02854Y00364D02*
D01*
X02854Y00364*
X02854Y00363*
X02854Y00363*
X02854Y00363*
X02854Y00363*
X02854Y00363*
X02854Y00363*
X02854Y00363*
X02854Y00363*
X02854Y00363*
X02854Y00363*
X02854Y00362*
X02818Y00365D02*
D01*
X02818Y00365*
X02818Y00364*
X02818Y00364*
X02819Y00364*
X02819Y00364*
X02819Y00363*
X02819Y00363*
X02819Y00363*
X02819Y00363*
X02819Y00363*
X02819Y00363*
X02819Y00362*
X02664D02*
D01*
X02664Y00363*
X02665Y00363*
X02665Y00363*
X02665Y00363*
X02665Y00363*
X02665Y00363*
X02665Y00363*
X02665Y00363*
X02665Y00363*
X02665Y00364*
X02665Y00364*
X02665Y00364*
X02349Y00362D02*
D01*
X02349Y00363*
X0235Y00363*
X0235Y00363*
X0235Y00363*
X0235Y00363*
X0235Y00363*
X0235Y00363*
X0235Y00363*
X0235Y00364*
X0235Y00364*
X0235Y00364*
Y00364*
X02979Y00362D02*
D01*
X02979Y00363*
X02979Y00363*
X0298Y00363*
X0298Y00363*
X0298Y00363*
X0298Y00363*
X0298Y00363*
X0298Y00363*
X0298Y00363*
X0298Y00363*
X0298Y00364*
X0298Y00364*
X02349Y00329D02*
D01*
X02349Y00329*
X02349Y00328*
X02349Y00328*
X02349Y00328*
X02349Y00328*
X02349Y00328*
X02349Y00328*
X02349Y00328*
X02349Y00327*
X02349Y00327*
X02349Y00327*
Y00327*
X02348Y00137D02*
D01*
X02348Y00138*
X02348Y00138*
X02349Y00138*
X02349Y00138*
X02349Y00139*
X02349Y00139*
X02349Y00139*
X02349Y0014*
X02349Y0014*
X02349Y0014*
X02349Y00141*
X02349Y00141*
X02387Y00137D02*
D01*
X02388Y00138*
X02388Y00138*
X02388Y00138*
X02388Y00139*
X02389Y00139*
X02389Y0014*
X02389Y0014*
X02389Y00141*
X02389Y00141*
X02389Y00142*
X02389Y00142*
X02389Y00142*
X02466Y00137D02*
D01*
X02466Y00138*
X02467Y00138*
X02467Y00139*
X02467Y00139*
X02468Y0014*
X02468Y0014*
X02468Y00141*
X02468Y00141*
X02468Y00142*
X02468Y00142*
X02468Y00143*
X02468Y00143*
X02505Y00137D02*
D01*
X02506Y00138*
X02507Y00139*
X02508Y00141*
X02509Y00142*
X02509Y00143*
X0251Y00144*
X0251Y00146*
X02511Y00147*
X02511Y00148*
X02511Y0015*
X02511Y00151*
X02511Y00152*
X02663Y00137D02*
D01*
X02663Y00138*
X02663Y00138*
X02664Y00138*
X02664Y00138*
X02664Y00139*
X02664Y00139*
X02664Y00139*
X02664Y0014*
X02664Y0014*
X02664Y0014*
X02664Y00141*
X02664Y00141*
X02702Y00137D02*
D01*
X02703Y00138*
X02703Y00138*
X02703Y00138*
X02703Y00139*
X02704Y00139*
X02704Y0014*
X02704Y0014*
X02704Y00141*
X02704Y00141*
X02704Y00142*
X02704Y00142*
X02704Y00142*
X02821Y00324D02*
D01*
X02821Y00325*
X02821Y00325*
X02821Y00326*
X02821Y00326*
X02821Y00326*
X02821Y00327*
X0282Y00327*
X0282Y00328*
X0282Y00328*
X0282Y00328*
X02819Y00329*
X02819Y00329*
Y0014D02*
D01*
X02819Y0014*
X02819Y00139*
X02819Y00139*
X02819Y00139*
X0282Y00139*
X0282Y00138*
X0282Y00138*
X0282Y00138*
X0282Y00138*
X0282Y00138*
X0282Y00137*
X0282Y00137*
X02854Y0015D02*
D01*
X02854Y00149*
X02855Y00148*
X02855Y00146*
X02855Y00145*
X02855Y00144*
X02856Y00143*
X02856Y00142*
X02857Y00141*
X02858Y00139*
X02859Y00138*
X0286Y00138*
X0286Y00137*
X03019Y00329D02*
D01*
X03019Y00328*
X03019Y00328*
X03019Y00328*
X03019Y00328*
X03018Y00327*
X03018Y00327*
X03018Y00327*
X03018Y00326*
X03018Y00326*
X03018Y00326*
X03018Y00325*
X03018Y00325*
X03017Y00137D02*
D01*
X03018Y00138*
X03018Y00138*
X03018Y00138*
X03018Y00139*
X03019Y00139*
X03019Y0014*
X03019Y0014*
X03019Y00141*
X03019Y00141*
X03019Y00142*
X03019Y00142*
X03019Y00142*
X02979Y00329D02*
D01*
X02979Y00329*
X02979Y00328*
X02979Y00328*
X02979Y00328*
X02979Y00328*
X02979Y00328*
X02979Y00328*
X02979Y00327*
X02979Y00327*
X02979Y00327*
X02979Y00327*
X02979Y00327*
X02978Y00137D02*
D01*
X02978Y00138*
X02978Y00138*
X02979Y00138*
X02979Y00138*
X02979Y00139*
X02979Y00139*
X02979Y00139*
X02979Y0014*
X02979Y0014*
X02979Y0014*
X02979Y00141*
X02979Y00141*
X02979Y00111D02*
D01*
X02979Y00111*
X02979Y00111*
X02979Y00111*
X02979Y00111*
X02979Y00111*
X02979Y00111*
X02979Y00112*
X02979Y00112*
X02979Y00112*
X02979Y00112*
X02979Y00112*
X02979Y00112*
X02467Y00111D02*
D01*
X02467Y00111*
X02467Y00111*
X02467Y00111*
X02467Y00111*
X02467Y00111*
X02467*
D01*
X02467Y00111*
X02467Y00111*
X02468Y00111*
X02468Y00112*
X02468Y00112*
X02468Y00112*
X02468Y00113*
X02468Y00113*
X02468Y00113*
X02468Y00114*
X02468Y00114*
X02468Y00114*
X02664Y00111D02*
D01*
X02664Y00111*
X02664Y00111*
X02664Y00111*
X02664Y00111*
X02664Y00111*
X02664Y00111*
X02664Y00112*
X02664Y00112*
X02664Y00112*
X02664Y00112*
X02664Y00112*
Y00112*
X02854Y00125D02*
D01*
X02854Y00124*
X02855Y00123*
X02855Y00121*
X02855Y0012*
X02856Y00118*
X02856Y00117*
X02857Y00116*
X02858Y00114*
X02858Y00113*
X02859Y00112*
X0286Y00111*
X02861Y00111*
D01*
X02861Y00111*
X02861Y00111*
X02861Y00111*
X02861Y00111*
X02861Y00111*
X02703D02*
D01*
X02703Y00111*
X02703Y00111*
X02704Y00111*
X02704Y00112*
X02704Y00112*
X02704Y00112*
X02704Y00112*
X02704Y00113*
X02704Y00113*
X02704Y00113*
X02704Y00114*
X02704Y00114*
X02468Y00363D02*
Y00405D01*
Y00363D02*
X02468Y00362D01*
X02511Y00363D02*
Y00405D01*
Y00363D02*
X02511Y00362D01*
X0298Y00408D02*
X0298Y00409D01*
X0298Y00409*
X0298Y00364D02*
Y00407D01*
X02818Y00365D02*
Y00403D01*
X02469Y0041D02*
X02469Y0041D01*
X02468Y00405D02*
X02468Y00407D01*
X02469Y0041D02*
X02469Y0041D01*
X02854Y00364D02*
Y00405D01*
X02665Y00364D02*
Y00405D01*
X02704Y00363D02*
X02704Y00362D01*
X02704Y00363D02*
Y00405D01*
X0235Y00364D02*
Y00405D01*
X02389Y00363D02*
X02389Y00362D01*
X02389Y00363D02*
Y00405D01*
X03019Y00363D02*
X03019Y00362D01*
X03019Y00363D02*
Y00405D01*
X02349Y00141D02*
Y00329D01*
X02389Y00142D02*
Y00329D01*
X02468Y00143D02*
Y00329D01*
X02511Y00152D02*
Y00329D01*
X02664Y00141D02*
Y00329D01*
X02704Y00142D02*
Y00329D01*
X02819Y0014D02*
Y00329D01*
X02854Y0015D02*
Y00329D01*
X03019Y00142D02*
Y00329D01*
X02979Y00141D02*
Y00329D01*
G54D50*
X01915Y00137D03*
X02545D03*
X02624D03*
X02899D03*
X03057D03*
X02742D03*
X02938D03*
X02781D03*
X02309D03*
X02427D03*
X02584D03*
X02072D03*
X02033D03*
X01994D03*
X01954D03*
X0219D03*
X02348D03*
X02387D03*
X02466D03*
X02505D03*
X0282D03*
X02663D03*
X0286D03*
X02978D03*
X03017D03*
X02702D03*
X02112D03*
X02151D03*
X01836D03*
X01875D03*
X03096D03*
G54D51*
X01797Y00157D03*
G54D62*
X02632Y02971D03*
Y03042D03*
G54D64*
X02349Y00329D03*
Y00362D03*
X02389D03*
Y00329D03*
X02468D03*
Y00362D03*
X02511D03*
Y00329D03*
X02664Y00362D03*
Y00329D03*
X02704Y00362D03*
Y00329D03*
X02819Y00362D03*
Y00329D03*
X02854D03*
Y00362D03*
X02979D03*
Y00329D03*
X03019Y00362D03*
Y00329D03*
X02711Y03003D03*
Y03036D03*
G54D71*
X02398Y02944D03*
X02327D03*
G54D72*
X02385Y02854D03*
X02351D03*
G54D77*
X02334Y03279D03*
Y032D03*
Y03121D03*
Y03042D03*
X02509Y03279D03*
Y03121D03*
Y032D03*
Y03042D03*
G54D143*
X00299Y01006D03*
Y00806D03*
X00099D03*
Y01006D03*
X00299Y02581D03*
Y02381D03*
X00099D03*
Y02581D03*
X00299Y02056D03*
Y01856D03*
X00099D03*
Y02056D03*
X00299Y01531D03*
Y01331D03*
X00099D03*
Y01531D03*
G54D150*
X00285Y04152D03*
Y00368D03*
G54D153*
X02891Y00243D02*
D01*
X0289Y00244*
X02888Y00245*
X02887Y00246*
X02886Y00247*
X02885Y00247*
X02884Y00248*
X02882Y00248*
X02881Y00249*
X0288Y00249*
X02878Y00249*
X02878Y00249*
X02436Y00235D02*
D01*
X02435Y00234*
X02434Y00233*
X02433Y00232*
X02432Y00231*
X02431Y0023*
X0243Y00229*
X0243Y00228*
X02429Y00226*
X02429Y00225*
X02428Y00224*
X02428Y00222*
X02428Y00221*
X02427Y0022*
X02427Y00218*
X02139Y03611D02*
X02342D01*
X02719Y03786D02*
X02719Y03786D01*
X02878Y00249D02*
X02878D01*
X02891Y00243D02*
X02891Y00243D01*
X02898Y00235*
X02427Y00111D02*
Y00218D01*
X02436Y00235D02*
X02447Y00242D01*
X02624Y00235D02*
X02636Y00247D01*
X02799Y00251D02*
X02799D01*
X02546Y00111D02*
Y00244D01*
X03059Y00231D02*
X03079Y00251D01*
X03097*
X01849Y00269D02*
X01876Y00243D01*
X01916Y00111D02*
Y00244D01*
X02934Y00141D02*
Y00224D01*
X02782Y00235D02*
X02799Y00251D01*
X02742Y0024D02*
X02753Y00251D01*
X02923Y00235D02*
X02934Y00224D01*
X02624Y00111D02*
Y00235D01*
X03058Y00139D02*
X03059Y0014D01*
X02934Y00141D02*
X02935Y00141D01*
X02742Y00137D02*
Y0024D01*
X02753Y00251D02*
X02799D01*
X02898Y00138D02*
X02899Y00137D01*
X02898Y00138D02*
Y00235D01*
X02923*
X03058Y00111D02*
Y00139D01*
X03059Y0014D02*
Y00231D01*
X03057Y00111D02*
X03058Y00111D01*
X02782Y00139D02*
Y00235D01*
X02309Y00111D02*
Y00246D01*
X0219Y00112D02*
X02191Y00111D01*
X02781Y00137D02*
X02782Y00139D01*
X02935Y00141D02*
X02938Y00137D01*
X03057D02*
X03058Y00139D01*
X05985Y02782D02*
X05994Y02791D01*
X04511Y02782D02*
X05985D01*
X04503Y02789D02*
X04511Y02782D01*
X03157Y02485D02*
Y0318D01*
Y02485D02*
X03368Y02273D01*
X02774Y03562D02*
X03157Y0318D01*
X07004Y01611D02*
Y02546D01*
X06729Y01336D02*
X07004Y01611D01*
X06424Y03126D02*
X07004Y02546D01*
X03889Y00771D02*
X04339Y0122D01*
X05994Y03556D02*
X06424Y03126D01*
X02774Y03562D02*
Y03566D01*
X02114Y00288D02*
X02151Y00252D01*
X02112Y00255D02*
D01*
Y00137D02*
Y00255D01*
X02151Y00112D02*
Y00252D01*
X01876Y00111D02*
Y00243D01*
X01837Y00111D02*
Y00257D01*
X02151Y00112D02*
X02152Y00111D01*
X01837Y00257D02*
X01849Y00269D01*
X03219Y03806D02*
X03224Y03811D01*
X03218Y03805D02*
X03219Y03806D01*
X02722Y03786D02*
X02784D01*
X02719D02*
X02722D01*
X03571Y02033D02*
Y02058D01*
X02632Y03042D02*
X02638Y03036D01*
X02632Y03042D02*
X02632Y03042D01*
X02509Y03042D02*
X02632D01*
X02638Y03036D02*
X02711D01*
X03571Y0201D02*
Y02033D01*
X0358Y01878D02*
Y02001D01*
Y01878D02*
X03639Y01819D01*
X03571Y0201D02*
X0358Y02001D01*
X03559Y01739D02*
X03639Y01819D01*
X02998Y03811D02*
X03004Y03805D01*
X03218*
X02784Y03786D02*
X02809Y03811D01*
X03534D02*
X03539Y03806D01*
X03368Y02252D02*
X03549Y02071D01*
X03368Y02252D02*
Y02273D01*
X05274Y03511D02*
X05994Y02791D01*
X06284Y02501*
X036Y0106D02*
Y01432D01*
X03559Y01473D02*
X036Y01432D01*
X03559Y01473D02*
Y01739D01*
X036Y0106D02*
X03889Y00771D01*
X04044Y03566D02*
X04254Y03776D01*
X02774Y03566D02*
X04044D01*
X04339Y0122D02*
X06404D01*
X06844Y01661*
X06424Y02181D02*
Y03126D01*
G54D157*
X03958Y04126D03*
X03784D03*
G54D158*
X03294Y04086D03*
X02994D03*
G54D159*
X05327Y02307D03*
X05127D03*
X04927D03*
X04727D03*
X04927Y01007D03*
X05127D03*
X04327Y02307D03*
X05327Y01007D03*
G54D160*
X04327Y01007D03*
G54D161*
X05578Y0089D03*
Y01689D03*
Y02489D03*
X03979D03*
Y0089D03*
X04062Y02595D03*
X0418D03*
X04298D03*
G54D162*
X05723Y04025D03*
Y03844D03*
X069Y03806D03*
Y03589D03*
X06734D03*
Y03806D03*
X06569Y03589D03*
Y03806D03*
G54D163*
X05934Y03937D03*
G54D164*
X06119Y04056D03*
G54D165*
X06119Y03819D03*
G54D166*
X00199Y00906D03*
Y02481D03*
Y01956D03*
Y01431D03*
G54D167*
X03571Y02097D03*
Y01309D03*
X02203Y02438D03*
X01696Y01309D03*
Y02097D03*
X02203Y00958D03*
X0299D03*
X0299Y02438D03*
G54D168*
X02043Y04157D03*
Y04057D03*
X01457Y04153D03*
Y04053D03*
G54D169*
X02043Y04257D03*
X01457Y04253D03*
G54D170*
X069Y04093D03*
X06569D03*
G54D171*
X02494Y02661D03*
X02692Y02721D03*
X02511Y00405D03*
X0261Y00279D03*
X02578D03*
X0298Y00409D03*
X02821Y00407D03*
X02748Y00282D03*
X02469Y0041D03*
X02905Y00279D03*
X02878Y00249D03*
X02692Y00795D03*
X02665D03*
X02854Y00405D03*
X02779Y00279D03*
X02665Y00405D03*
X02704D03*
X0235D03*
X02389D03*
X02937Y00279D03*
X02957Y00251D03*
X03019Y00405D03*
X0274Y00976D03*
X02767D03*
X02732Y00795D03*
X02681Y00976D03*
X02708D03*
X02447Y00242D03*
X02413Y00279D03*
X02444D03*
X02606Y00931D03*
X02625Y00795D03*
X02598D03*
X02636Y00247D03*
X02799Y00251D03*
X02826Y00976D03*
X02799D03*
X02649D03*
X02622D03*
X02759Y00795D03*
X02799D03*
X02826D03*
X02862D03*
X02893D03*
X02409Y01088D03*
X02311Y0109D03*
X02508Y00931D03*
X02409Y00932D03*
X02724Y01093D03*
X02784Y01094D03*
X02842Y01095D03*
X02546Y00244D03*
X03097Y00251D03*
X02475Y02291D03*
X0233Y02215D03*
X01798Y01304D03*
X02606Y01091D03*
X03554Y01841D03*
X03719Y01996D03*
X03894Y01566D03*
X03379Y01386D03*
X01721Y0189D03*
X01671Y01792D03*
X01674Y01989D03*
X02508Y0109D03*
X03413Y01573D03*
X0167Y01595D03*
X01754Y02126D03*
X02409Y02579D03*
X02586Y02569D03*
X03197Y01714D03*
X03439Y0187D03*
X03298Y01971D03*
X02985Y02287D03*
X02702Y02289D03*
X02821Y02601D03*
X01718Y01792D03*
X02881Y02566D03*
X03732Y01418D03*
X03554Y01891D03*
X02253Y02279D03*
X02272Y02463D03*
X01719Y01536D03*
X02311Y00934D03*
X03571Y02033D03*
X03554Y01991D03*
X02942Y02286D03*
X02841Y02263D03*
X02394Y0272D03*
X01567Y01285D03*
X01675Y01891D03*
X01568Y02067D03*
X02783Y02429D03*
X03719Y01921D03*
X03773Y01666D03*
X02599Y02436D03*
X02494Y02696D03*
X02894Y02431D03*
X02665Y01092D03*
X02475Y02456D03*
X03414Y01805D03*
X03404Y01363D03*
X02579Y02281D03*
X02685Y02311D03*
X0359Y01662D03*
X02404Y02412D03*
X02803Y02307D03*
X01716Y01399D03*
X01721Y01989D03*
X01619Y02121D03*
X03549Y01413D03*
X02488Y02413D03*
X02726Y02293D03*
X01822Y01674D03*
X0167Y01694D03*
X01884Y02071D03*
X02901Y01095D03*
X0292Y02428D03*
X01893Y01693D03*
X03594Y01514D03*
X0245Y02282D03*
X02409Y02314D03*
X02958Y02621D03*
X03406Y01461D03*
X0341Y01713D03*
X03252Y01661D03*
X02933Y00953D03*
X02871Y02297D03*
X02685Y02568D03*
X03571Y02058D03*
X03804Y0184D03*
X01879Y01811D03*
X03554Y01941D03*
X03392Y01871D03*
X03407Y01411D03*
X02575Y02412D03*
X02499Y02236D03*
X02409Y02283D03*
X02783Y02568D03*
X02948Y02456D03*
X03549Y01441D03*
X03718Y01713D03*
X02624Y02461D03*
X01897Y01516D03*
X03834Y01481D03*
X03864Y01511D03*
X03924Y01536D03*
X03719Y01766D03*
X03329Y01826D03*
X02645Y02274D03*
X02665Y02291D03*
X01721Y01694D03*
X01671Y01399D03*
X02581Y02308D03*
X03803Y01691D03*
X03224Y01661D03*
X02252Y02613D03*
X01718Y01497D03*
X01714Y01595D03*
X01671Y01497D03*
X02321Y02586D03*
X03379Y01336D03*
X01797Y00355D03*
X02034Y00246D03*
X01916Y00244D03*
X02309Y00246D03*
X0333Y03301D03*
X0412Y03594D03*
X01393Y01816D03*
X0099Y00687D03*
X04794Y02808D03*
X03183Y03135D03*
X03277Y02963D03*
X03197Y0297D03*
X03491Y03103D03*
X03188Y03187D03*
X0323Y03235D03*
X03358Y03448D03*
X03068Y03395D03*
X02419Y02788D03*
X02146Y02753D03*
X03275Y03141D03*
X03056Y01811D03*
X02413Y03295D03*
X02254Y03536D03*
X02579Y03486D03*
X02389Y03481D03*
X02321Y03361D03*
X02434Y03546D03*
X02634Y03406D03*
X02631Y02876D03*
X02591Y03186D03*
X0259Y03288D03*
X00996Y02256D03*
X02004Y01336D03*
X02028Y01361D03*
X02549Y01755D03*
X02418Y03118D03*
X02414Y03199D03*
X02462Y03172D03*
X02473Y0298D03*
X02146Y04103D03*
X02253Y04086D03*
X01408Y0398D03*
X01345Y04175D03*
X00996Y01187D03*
X00988Y01717D03*
X00937Y02317D03*
X02353Y04017D03*
X01726Y04329D03*
X01788D03*
X04477Y03135D03*
X04064Y02722D03*
X06628Y01372D03*
X04039Y02406D03*
X06974Y01939D03*
X04134Y01651D03*
X03994Y01551D03*
X04134Y01751D03*
X04151Y01623D03*
X03968Y01671D03*
X03969Y01552D03*
X03944Y01816D03*
X04131Y01686D03*
X04179Y01601D03*
X04034Y01546D03*
X03996Y01711D03*
X04064Y01796D03*
Y01511D03*
X03263Y03303D03*
X0396Y02724D03*
X01569Y04171D03*
X02076Y00255D03*
Y00287D03*
X02112D03*
X02151D03*
X02112Y00255D03*
X02151D03*
X01832D03*
X01852D03*
X01872D03*
X01832Y00287D03*
X01852D03*
X01872D03*
X06253Y02909D03*
X06647Y03129D03*
X05267Y04088D03*
X04339Y02725D03*
X04503Y02789D03*
X02231Y02584D03*
X05994Y03552D03*
X04049Y03665D03*
X03829Y03806D03*
X05577Y02214D03*
X02694Y01481D03*
X02384Y01941D03*
X0383Y03762D03*
X06334Y03266D03*
X03744Y03261D03*
X03395Y04222D03*
X04272Y03135D03*
X05634Y02236D03*
X02626Y0177D03*
X06304Y03121D03*
X03939D03*
X02139Y03738D03*
X04208Y03135D03*
X02604Y01734D03*
X06626Y03032D03*
X04152Y03135D03*
X02299Y01916D03*
X02724Y03521D03*
X01248Y02D03*
X02579Y0179D03*
X04068Y03135D03*
X02674Y03501D03*
X04234Y02725D03*
X06456Y03009D03*
X01691Y04079D03*
X03642Y00636D03*
X02259Y03261D03*
X03374Y03273D03*
X03368Y0305D03*
X04039Y03784D03*
X06476Y03231D03*
X04333Y03135D03*
X01557Y04229D03*
X06282Y03226D03*
X03806Y03235D03*
X01261Y02482D03*
X04114Y03135D03*
X06648Y03341D03*
X02888Y04221D03*
X0337Y02888D03*
X02258Y03741D03*
X01749Y0411D03*
X0257Y04283D03*
X01459Y03147D03*
X0144Y03557D03*
X01903Y04018D03*
X0229Y04217D03*
X0388Y03109D03*
X03623Y02587D03*
X03622Y03486D03*
X03491Y03297D03*
X03542Y03319D03*
X03344Y02996D03*
X03744Y03342D03*
X03653Y03293D03*
X03394Y03447D03*
X03436Y03457D03*
X03717Y03072D03*
X02799Y03616D03*
X03589Y01711D03*
X05733Y03556D03*
X05676Y03546D03*
X03603Y00682D03*
X02478Y00937D03*
X06548Y01531D03*
X06602Y01612D03*
Y01672D03*
Y01722D03*
X06601Y01777D03*
X06685Y01828D03*
X06699Y01881D03*
X06949Y02095D03*
X06607Y02176D03*
X06395Y02111D03*
X06048Y02171D03*
X06004Y02434D03*
X06274Y02391D03*
X06398Y02453D03*
X06397Y02501D03*
X06396Y02556D03*
X06397Y0261D03*
X06398Y02657D03*
X06372Y02909D03*
X0491Y04203D03*
X04387Y04206D03*
X03777Y04023D03*
X04085Y03892D03*
X04194Y03884D03*
X04431Y03135D03*
X0286Y03787D03*
X02724Y03729D03*
X03531Y0366D03*
X03269Y03788D03*
X01242Y01472D03*
X01256Y00942D03*
X00654Y0079D03*
X00655Y01028D03*
X00654Y01314D03*
X00653Y01551D03*
X00654Y01839D03*
Y02073D03*
Y02365D03*
X00653Y02593D03*
X02206Y01298D03*
X02205Y032D03*
X02502Y01316D03*
X02525Y02463D03*
X03342Y02263D03*
X03498Y02341D03*
X02429Y02621D03*
X01004Y00906D03*
X02446Y01437D03*
X01008Y0143D03*
X02409Y01967D03*
X01009Y01956D03*
X0102Y02481D03*
X02643Y01616D03*
X02666Y0164D03*
X01884Y03601D03*
X01754Y03661D03*
X03424Y03636D03*
X01549Y03621D03*
X03239Y03596D03*
X01574D03*
X03539Y03806D03*
X03219D03*
X02722Y03786D03*
X02139Y03611D03*
X02084Y03896D03*
X02083Y01411D03*
X02059Y01386D03*
Y03871D03*
X02029Y03836D03*
X01294Y04256D03*
X02004Y03816D03*
X02234Y03506D03*
X03529Y03481D03*
X05274Y03511D03*
X06284Y02501D03*
X02679Y03661D03*
X02774Y03566D03*
X02993Y03751D03*
X03699D03*
X03014Y03831D03*
X03699Y03836D03*
X04254Y03776D03*
X02894Y01561D03*
X02919Y01536D03*
X02274Y01506D03*
X02719Y01591D03*
X03724Y01675D03*
X06844Y01661D03*
X06424Y02181D03*
X06309Y03199D03*
X06339Y03151D03*
X04754Y04115D03*
X01779Y04156D03*
X03504Y04086D03*
X03854Y03151D03*
X03829Y03176D03*
X03799Y03201D03*
X06439Y03191D03*
X06354Y03331D03*
X06444Y03291D03*
X03302Y03344D03*
X06409Y03371D03*
X06447Y03396D03*
X06479Y03426D03*
X06509Y03456D03*
X03469D03*
X01849Y03701D03*
X06294D03*
G54D172*
X02531Y03853D03*
Y0283D03*
X00149D03*
Y03853D03*
G54D173*
X0213Y00268D03*
X01851Y00269D03*
M02*